(kicad_sch (version 20230121) (generator eeschema)

  (paper "A3")

  (title_block
    (title "Scalenode CM4 Baseboard")
    (date "2024-03-26")
    (rev "1.1.3")
    (company "Antmicro")
    (comment 1 "www.antmicro.com")
  )

  (junction (at 254 125.73) (diameter 0) (color 0 0 0 0)
  )
  (junction (at 233.68 179.07) (diameter 0) (color 0 0 0 0)
  )
  (junction (at 233.68 171.45) (diameter 0) (color 0 0 0 0)
  )
  (junction (at 133.35 105.41) (diameter 0) (color 0 0 0 0)
  )
  (junction (at 152.4 120.65) (diameter 0) (color 0 0 0 0)
  )
  (junction (at 133.35 171.45) (diameter 0) (color 0 0 0 0)
  )
  (junction (at 254 201.93) (diameter 0) (color 0 0 0 0)
  )
  (junction (at 133.35 118.11) (diameter 0) (color 0 0 0 0)
  )
  (junction (at 149.86 179.07) (diameter 0) (color 0 0 0 0)
  )
  (junction (at 233.68 194.31) (diameter 0) (color 0 0 0 0)
  )
  (junction (at 133.35 95.25) (diameter 0) (color 0 0 0 0)
  )
  (junction (at 133.35 130.81) (diameter 0) (color 0 0 0 0)
  )
  (junction (at 233.68 118.11) (diameter 0) (color 0 0 0 0)
  )
  (junction (at 152.4 161.29) (diameter 0) (color 0 0 0 0)
  )
  (junction (at 133.35 143.51) (diameter 0) (color 0 0 0 0)
  )
  (junction (at 133.35 161.29) (diameter 0) (color 0 0 0 0)
  )
  (junction (at 152.4 146.05) (diameter 0) (color 0 0 0 0)
  )
  (junction (at 233.68 110.49) (diameter 0) (color 0 0 0 0)
  )
  (junction (at 152.4 95.25) (diameter 0) (color 0 0 0 0)
  )
  (junction (at 254 163.83) (diameter 0) (color 0 0 0 0)
  )
  (junction (at 149.86 181.61) (diameter 0) (color 0 0 0 0)
  )
  (junction (at 254 171.45) (diameter 0) (color 0 0 0 0)
  )
  (junction (at 133.35 87.63) (diameter 0) (color 0 0 0 0)
  )
  (junction (at 233.68 133.35) (diameter 0) (color 0 0 0 0)
  )
  (junction (at 233.68 201.93) (diameter 0) (color 0 0 0 0)
  )
  (junction (at 233.68 148.59) (diameter 0) (color 0 0 0 0)
  )
  (junction (at 152.4 168.91) (diameter 0) (color 0 0 0 0)
  )
  (junction (at 129.54 186.69) (diameter 0) (color 0 0 0 0)
  )
  (junction (at 233.68 102.87) (diameter 0) (color 0 0 0 0)
  )
  (junction (at 135.89 189.23) (diameter 0) (color 0 0 0 0)
  )
  (junction (at 254 186.69) (diameter 0) (color 0 0 0 0)
  )
  (junction (at 152.4 133.35) (diameter 0) (color 0 0 0 0)
  )
  (junction (at 254 118.11) (diameter 0) (color 0 0 0 0)
  )
  (junction (at 133.35 201.93) (diameter 0) (color 0 0 0 0)
  )
  (junction (at 233.68 156.21) (diameter 0) (color 0 0 0 0)
  )
  (junction (at 254 156.21) (diameter 0) (color 0 0 0 0)
  )
  (junction (at 135.89 186.69) (diameter 0) (color 0 0 0 0)
  )
  (junction (at 254 110.49) (diameter 0) (color 0 0 0 0)
  )
  (junction (at 254 102.87) (diameter 0) (color 0 0 0 0)
  )
  (junction (at 254 148.59) (diameter 0) (color 0 0 0 0)
  )
  (junction (at 133.35 153.67) (diameter 0) (color 0 0 0 0)
  )
  (junction (at 190.5 220.98) (diameter 0) (color 0 0 0 0)
  )
  (junction (at 149.86 184.15) (diameter 0) (color 0 0 0 0)
  )
  (junction (at 152.4 153.67) (diameter 0) (color 0 0 0 0)
  )
  (junction (at 233.68 95.25) (diameter 0) (color 0 0 0 0)
  )
  (junction (at 181.61 210.82) (diameter 0) (color 0 0 0 0)
  )
  (junction (at 233.68 186.69) (diameter 0) (color 0 0 0 0)
  )
  (junction (at 254 179.07) (diameter 0) (color 0 0 0 0)
  )
  (junction (at 233.68 125.73) (diameter 0) (color 0 0 0 0)
  )
  (junction (at 254 194.31) (diameter 0) (color 0 0 0 0)
  )
  (junction (at 152.4 107.95) (diameter 0) (color 0 0 0 0)
  )
  (junction (at 152.4 87.63) (diameter 0) (color 0 0 0 0)
  )
  (junction (at 233.68 140.97) (diameter 0) (color 0 0 0 0)
  )
  (junction (at 254 95.25) (diameter 0) (color 0 0 0 0)
  )
  (junction (at 149.86 186.69) (diameter 0) (color 0 0 0 0)
  )
  (junction (at 233.68 163.83) (diameter 0) (color 0 0 0 0)
  )

  (no_connect (at 327.025 143.51))
  (no_connect (at 149.86 102.87))
  (no_connect (at 237.49 82.55))
  (no_connect (at 135.89 168.91))
  (no_connect (at 327.025 116.205))
  (no_connect (at 135.89 158.75))
  (no_connect (at 327.025 125.095))
  (no_connect (at 149.86 171.45))
  (no_connect (at 327.025 134.62))
  (no_connect (at 135.89 166.37))
  (no_connect (at 135.89 163.83))
  (no_connect (at 237.49 85.09))

  (wire (pts (xy 176.53 105.41) (xy 177.8 105.41))
    (stroke (width 0) (type default))
  )
  (wire (pts (xy 251.46 118.11) (xy 254 118.11))
    (stroke (width 0) (type default))
  )
  (wire (pts (xy 149.86 176.53) (xy 149.86 179.07))
    (stroke (width 0) (type default))
  )
  (wire (pts (xy 233.68 171.45) (xy 233.68 179.07))
    (stroke (width 0) (type default))
  )
  (wire (pts (xy 135.89 181.61) (xy 124.46 181.61))
    (stroke (width 0) (type default))
  )
  (wire (pts (xy 251.46 204.47) (xy 262.89 204.47))
    (stroke (width 0) (type default))
  )
  (wire (pts (xy 135.89 92.71) (xy 124.46 92.71))
    (stroke (width 0) (type default))
  )
  (wire (pts (xy 135.89 153.67) (xy 133.35 153.67))
    (stroke (width 0) (type default))
  )
  (wire (pts (xy 251.46 194.31) (xy 254 194.31))
    (stroke (width 0) (type default))
  )
  (wire (pts (xy 149.86 181.61) (xy 149.86 184.15))
    (stroke (width 0) (type default))
  )
  (wire (pts (xy 161.29 118.11) (xy 149.86 118.11))
    (stroke (width 0) (type default))
  )
  (wire (pts (xy 251.46 90.17) (xy 262.89 90.17))
    (stroke (width 0) (type default))
  )
  (wire (pts (xy 135.89 140.97) (xy 124.46 140.97))
    (stroke (width 0) (type default))
  )
  (wire (pts (xy 133.35 171.45) (xy 133.35 201.93))
    (stroke (width 0) (type default))
  )
  (wire (pts (xy 135.89 107.95) (xy 124.46 107.95))
    (stroke (width 0) (type default))
  )
  (wire (pts (xy 124.46 186.69) (xy 129.54 186.69))
    (stroke (width 0) (type default))
  )
  (wire (pts (xy 135.89 133.35) (xy 124.46 133.35))
    (stroke (width 0) (type default))
  )
  (wire (pts (xy 237.49 105.41) (xy 226.06 105.41))
    (stroke (width 0) (type default))
  )
  (wire (pts (xy 152.4 107.95) (xy 152.4 120.65))
    (stroke (width 0) (type default))
  )
  (wire (pts (xy 135.89 191.77) (xy 135.89 189.23))
    (stroke (width 0) (type default))
  )
  (wire (pts (xy 237.49 163.83) (xy 233.68 163.83))
    (stroke (width 0) (type default))
  )
  (wire (pts (xy 129.54 186.69) (xy 135.89 186.69))
    (stroke (width 0) (type default))
  )
  (wire (pts (xy 237.49 113.03) (xy 226.06 113.03))
    (stroke (width 0) (type default))
  )
  (wire (pts (xy 152.4 133.35) (xy 152.4 146.05))
    (stroke (width 0) (type default))
  )
  (wire (pts (xy 161.29 143.51) (xy 149.86 143.51))
    (stroke (width 0) (type default))
  )
  (wire (pts (xy 135.89 115.57) (xy 124.46 115.57))
    (stroke (width 0) (type default))
  )
  (wire (pts (xy 233.68 186.69) (xy 233.68 194.31))
    (stroke (width 0) (type default))
  )
  (wire (pts (xy 251.46 201.93) (xy 254 201.93))
    (stroke (width 0) (type default))
  )
  (wire (pts (xy 251.46 173.99) (xy 262.89 173.99))
    (stroke (width 0) (type default))
  )
  (wire (pts (xy 161.29 158.75) (xy 149.86 158.75))
    (stroke (width 0) (type default))
  )
  (wire (pts (xy 135.89 90.17) (xy 124.46 90.17))
    (stroke (width 0) (type default))
  )
  (wire (pts (xy 237.49 156.21) (xy 233.68 156.21))
    (stroke (width 0) (type default))
  )
  (wire (pts (xy 135.89 82.55) (xy 124.46 82.55))
    (stroke (width 0) (type default))
  )
  (wire (pts (xy 251.46 184.15) (xy 262.89 184.15))
    (stroke (width 0) (type default))
  )
  (wire (pts (xy 237.49 143.51) (xy 226.06 143.51))
    (stroke (width 0) (type default))
  )
  (wire (pts (xy 149.86 110.49) (xy 161.29 110.49))
    (stroke (width 0) (type default))
  )
  (wire (pts (xy 251.46 140.97) (xy 262.89 140.97))
    (stroke (width 0) (type default))
  )
  (wire (pts (xy 233.68 156.21) (xy 233.68 163.83))
    (stroke (width 0) (type default))
  )
  (wire (pts (xy 149.86 100.33) (xy 161.29 100.33))
    (stroke (width 0) (type default))
  )
  (wire (pts (xy 251.46 102.87) (xy 254 102.87))
    (stroke (width 0) (type default))
  )
  (wire (pts (xy 237.49 173.99) (xy 226.06 173.99))
    (stroke (width 0) (type default))
  )
  (wire (pts (xy 237.49 194.31) (xy 233.68 194.31))
    (stroke (width 0) (type default))
  )
  (wire (pts (xy 149.86 85.09) (xy 161.29 85.09))
    (stroke (width 0) (type default))
  )
  (wire (pts (xy 251.46 176.53) (xy 262.89 176.53))
    (stroke (width 0) (type default))
  )
  (wire (pts (xy 251.46 135.89) (xy 262.89 135.89))
    (stroke (width 0) (type default))
  )
  (wire (pts (xy 135.89 135.89) (xy 124.46 135.89))
    (stroke (width 0) (type default))
  )
  (wire (pts (xy 251.46 171.45) (xy 254 171.45))
    (stroke (width 0) (type default))
  )
  (wire (pts (xy 237.49 199.39) (xy 226.06 199.39))
    (stroke (width 0) (type default))
  )
  (wire (pts (xy 251.46 153.67) (xy 262.89 153.67))
    (stroke (width 0) (type default))
  )
  (wire (pts (xy 149.86 97.79) (xy 161.29 97.79))
    (stroke (width 0) (type default))
  )
  (wire (pts (xy 251.46 138.43) (xy 262.89 138.43))
    (stroke (width 0) (type default))
  )
  (wire (pts (xy 149.86 115.57) (xy 161.29 115.57))
    (stroke (width 0) (type default))
  )
  (wire (pts (xy 233.68 194.31) (xy 233.68 201.93))
    (stroke (width 0) (type default))
  )
  (wire (pts (xy 237.49 90.17) (xy 226.06 90.17))
    (stroke (width 0) (type default))
  )
  (wire (pts (xy 149.86 153.67) (xy 152.4 153.67))
    (stroke (width 0) (type default))
  )
  (wire (pts (xy 237.49 107.95) (xy 226.06 107.95))
    (stroke (width 0) (type default))
  )
  (wire (pts (xy 251.46 97.79) (xy 262.89 97.79))
    (stroke (width 0) (type default))
  )
  (wire (pts (xy 135.89 125.73) (xy 124.46 125.73))
    (stroke (width 0) (type default))
  )
  (wire (pts (xy 133.35 87.63) (xy 133.35 95.25))
    (stroke (width 0) (type default))
  )
  (wire (pts (xy 152.4 120.65) (xy 152.4 133.35))
    (stroke (width 0) (type default))
  )
  (wire (pts (xy 237.49 201.93) (xy 233.68 201.93))
    (stroke (width 0) (type default))
  )
  (wire (pts (xy 237.49 118.11) (xy 233.68 118.11))
    (stroke (width 0) (type default))
  )
  (wire (pts (xy 133.35 143.51) (xy 133.35 153.67))
    (stroke (width 0) (type default))
  )
  (wire (pts (xy 149.86 120.65) (xy 152.4 120.65))
    (stroke (width 0) (type default))
  )
  (wire (pts (xy 152.4 95.25) (xy 152.4 107.95))
    (stroke (width 0) (type default))
  )
  (wire (pts (xy 135.89 87.63) (xy 133.35 87.63))
    (stroke (width 0) (type default))
  )
  (wire (pts (xy 251.46 82.55) (xy 262.89 82.55))
    (stroke (width 0) (type default))
  )
  (wire (pts (xy 135.89 176.53) (xy 124.46 176.53))
    (stroke (width 0) (type default))
  )
  (wire (pts (xy 237.49 151.13) (xy 226.06 151.13))
    (stroke (width 0) (type default))
  )
  (wire (pts (xy 237.49 204.47) (xy 226.06 204.47))
    (stroke (width 0) (type default))
  )
  (wire (pts (xy 135.89 204.47) (xy 124.46 204.47))
    (stroke (width 0) (type default))
  )
  (wire (pts (xy 149.86 181.61) (xy 149.86 179.07))
    (stroke (width 0) (type default))
  )
  (wire (pts (xy 251.46 125.73) (xy 254 125.73))
    (stroke (width 0) (type default))
  )
  (wire (pts (xy 251.46 199.39) (xy 262.89 199.39))
    (stroke (width 0) (type default))
  )
  (wire (pts (xy 233.68 201.93) (xy 233.68 214.63))
    (stroke (width 0) (type default))
  )
  (wire (pts (xy 254 87.63) (xy 254 95.25))
    (stroke (width 0) (type default))
  )
  (wire (pts (xy 251.46 156.21) (xy 254 156.21))
    (stroke (width 0) (type default))
  )
  (wire (pts (xy 237.49 146.05) (xy 226.06 146.05))
    (stroke (width 0) (type default))
  )
  (wire (pts (xy 254 201.93) (xy 254 214.63))
    (stroke (width 0) (type default))
  )
  (wire (pts (xy 135.89 138.43) (xy 124.46 138.43))
    (stroke (width 0) (type default))
  )
  (wire (pts (xy 237.49 191.77) (xy 226.06 191.77))
    (stroke (width 0) (type default))
  )
  (wire (pts (xy 135.89 148.59) (xy 124.46 148.59))
    (stroke (width 0) (type default))
  )
  (wire (pts (xy 237.49 125.73) (xy 233.68 125.73))
    (stroke (width 0) (type default))
  )
  (wire (pts (xy 237.49 171.45) (xy 233.68 171.45))
    (stroke (width 0) (type default))
  )
  (wire (pts (xy 149.86 95.25) (xy 152.4 95.25))
    (stroke (width 0) (type default))
  )
  (wire (pts (xy 237.49 133.35) (xy 233.68 133.35))
    (stroke (width 0) (type default))
  )
  (wire (pts (xy 152.4 161.29) (xy 152.4 168.91))
    (stroke (width 0) (type default))
  )
  (wire (pts (xy 149.86 146.05) (xy 152.4 146.05))
    (stroke (width 0) (type default))
  )
  (wire (pts (xy 237.49 128.27) (xy 226.06 128.27))
    (stroke (width 0) (type default))
  )
  (wire (pts (xy 233.68 133.35) (xy 233.68 140.97))
    (stroke (width 0) (type default))
  )
  (wire (pts (xy 149.86 107.95) (xy 152.4 107.95))
    (stroke (width 0) (type default))
  )
  (wire (pts (xy 237.49 110.49) (xy 233.68 110.49))
    (stroke (width 0) (type default))
  )
  (wire (pts (xy 133.35 95.25) (xy 133.35 105.41))
    (stroke (width 0) (type default))
  )
  (wire (pts (xy 133.35 161.29) (xy 133.35 171.45))
    (stroke (width 0) (type default))
  )
  (wire (pts (xy 135.89 179.07) (xy 124.46 179.07))
    (stroke (width 0) (type default))
  )
  (wire (pts (xy 133.35 201.93) (xy 133.35 213.36))
    (stroke (width 0) (type default))
  )
  (wire (pts (xy 251.46 148.59) (xy 254 148.59))
    (stroke (width 0) (type default))
  )
  (wire (pts (xy 237.49 115.57) (xy 226.06 115.57))
    (stroke (width 0) (type default))
  )
  (wire (pts (xy 152.4 146.05) (xy 152.4 153.67))
    (stroke (width 0) (type default))
  )
  (wire (pts (xy 152.4 80.01) (xy 152.4 87.63))
    (stroke (width 0) (type default))
  )
  (wire (pts (xy 149.86 199.39) (xy 161.29 199.39))
    (stroke (width 0) (type default))
  )
  (wire (pts (xy 190.5 196.85) (xy 190.5 201.93))
    (stroke (width 0) (type default))
  )
  (wire (pts (xy 149.86 135.89) (xy 161.29 135.89))
    (stroke (width 0) (type default))
  )
  (wire (pts (xy 237.49 166.37) (xy 226.06 166.37))
    (stroke (width 0) (type default))
  )
  (wire (pts (xy 251.46 181.61) (xy 262.89 181.61))
    (stroke (width 0) (type default))
  )
  (wire (pts (xy 251.46 189.23) (xy 262.89 189.23))
    (stroke (width 0) (type default))
  )
  (wire (pts (xy 251.46 95.25) (xy 254 95.25))
    (stroke (width 0) (type default))
  )
  (wire (pts (xy 237.49 102.87) (xy 233.68 102.87))
    (stroke (width 0) (type default))
  )
  (wire (pts (xy 251.46 151.13) (xy 262.89 151.13))
    (stroke (width 0) (type default))
  )
  (wire (pts (xy 135.89 161.29) (xy 133.35 161.29))
    (stroke (width 0) (type default))
  )
  (wire (pts (xy 233.68 148.59) (xy 233.68 156.21))
    (stroke (width 0) (type default))
  )
  (wire (pts (xy 251.46 196.85) (xy 262.89 196.85))
    (stroke (width 0) (type default))
  )
  (wire (pts (xy 149.86 156.21) (xy 161.29 156.21))
    (stroke (width 0) (type default))
  )
  (wire (pts (xy 133.35 118.11) (xy 133.35 130.81))
    (stroke (width 0) (type default))
  )
  (wire (pts (xy 233.68 179.07) (xy 233.68 186.69))
    (stroke (width 0) (type default))
  )
  (wire (pts (xy 161.29 181.61) (xy 149.86 181.61))
    (stroke (width 0) (type default))
  )
  (wire (pts (xy 237.49 92.71) (xy 226.06 92.71))
    (stroke (width 0) (type default))
  )
  (wire (pts (xy 233.68 95.25) (xy 233.68 102.87))
    (stroke (width 0) (type default))
  )
  (wire (pts (xy 149.86 125.73) (xy 161.29 125.73))
    (stroke (width 0) (type default))
  )
  (wire (pts (xy 152.4 153.67) (xy 152.4 161.29))
    (stroke (width 0) (type default))
  )
  (wire (pts (xy 177.8 210.82) (xy 181.61 210.82))
    (stroke (width 0) (type default))
  )
  (wire (pts (xy 251.46 113.03) (xy 262.89 113.03))
    (stroke (width 0) (type default))
  )
  (wire (pts (xy 135.89 105.41) (xy 133.35 105.41))
    (stroke (width 0) (type default))
  )
  (wire (pts (xy 149.86 113.03) (xy 161.29 113.03))
    (stroke (width 0) (type default))
  )
  (wire (pts (xy 254 179.07) (xy 254 186.69))
    (stroke (width 0) (type default))
  )
  (wire (pts (xy 135.89 97.79) (xy 124.46 97.79))
    (stroke (width 0) (type default))
  )
  (wire (pts (xy 233.68 125.73) (xy 233.68 133.35))
    (stroke (width 0) (type default))
  )
  (wire (pts (xy 237.49 97.79) (xy 226.06 97.79))
    (stroke (width 0) (type default))
  )
  (wire (pts (xy 251.46 115.57) (xy 262.89 115.57))
    (stroke (width 0) (type default))
  )
  (wire (pts (xy 149.86 140.97) (xy 161.29 140.97))
    (stroke (width 0) (type default))
  )
  (wire (pts (xy 149.86 87.63) (xy 152.4 87.63))
    (stroke (width 0) (type default))
  )
  (wire (pts (xy 135.89 173.99) (xy 124.46 173.99))
    (stroke (width 0) (type default))
  )
  (wire (pts (xy 162.56 105.41) (xy 168.91 105.41))
    (stroke (width 0) (type default))
  )
  (wire (pts (xy 181.61 210.82) (xy 182.88 210.82))
    (stroke (width 0) (type default))
  )
  (wire (pts (xy 177.8 105.41) (xy 177.8 93.98))
    (stroke (width 0) (type default))
  )
  (wire (pts (xy 135.89 171.45) (xy 133.35 171.45))
    (stroke (width 0) (type default))
  )
  (wire (pts (xy 135.89 143.51) (xy 133.35 143.51))
    (stroke (width 0) (type default))
  )
  (wire (pts (xy 167.64 210.82) (xy 172.72 210.82))
    (stroke (width 0) (type default))
  )
  (wire (pts (xy 149.86 138.43) (xy 161.29 138.43))
    (stroke (width 0) (type default))
  )
  (wire (pts (xy 135.89 151.13) (xy 124.46 151.13))
    (stroke (width 0) (type default))
  )
  (wire (pts (xy 251.46 92.71) (xy 262.89 92.71))
    (stroke (width 0) (type default))
  )
  (wire (pts (xy 149.86 130.81) (xy 161.29 130.81))
    (stroke (width 0) (type default))
  )
  (wire (pts (xy 135.89 113.03) (xy 124.46 113.03))
    (stroke (width 0) (type default))
  )
  (wire (pts (xy 135.89 123.19) (xy 124.46 123.19))
    (stroke (width 0) (type default))
  )
  (wire (pts (xy 237.49 158.75) (xy 226.06 158.75))
    (stroke (width 0) (type default))
  )
  (wire (pts (xy 251.46 87.63) (xy 254 87.63))
    (stroke (width 0) (type default))
  )
  (wire (pts (xy 149.86 161.29) (xy 152.4 161.29))
    (stroke (width 0) (type default))
  )
  (wire (pts (xy 237.49 161.29) (xy 226.06 161.29))
    (stroke (width 0) (type default))
  )
  (wire (pts (xy 233.68 163.83) (xy 233.68 171.45))
    (stroke (width 0) (type default))
  )
  (wire (pts (xy 254 148.59) (xy 254 156.21))
    (stroke (width 0) (type default))
  )
  (wire (pts (xy 237.49 176.53) (xy 226.06 176.53))
    (stroke (width 0) (type default))
  )
  (wire (pts (xy 133.35 130.81) (xy 133.35 143.51))
    (stroke (width 0) (type default))
  )
  (wire (pts (xy 181.61 210.82) (xy 181.61 213.36))
    (stroke (width 0) (type default))
  )
  (wire (pts (xy 251.46 143.51) (xy 262.89 143.51))
    (stroke (width 0) (type default))
  )
  (wire (pts (xy 135.89 189.23) (xy 124.46 189.23))
    (stroke (width 0) (type default))
  )
  (wire (pts (xy 149.86 204.47) (xy 161.29 204.47))
    (stroke (width 0) (type default))
  )
  (wire (pts (xy 233.68 87.63) (xy 233.68 95.25))
    (stroke (width 0) (type default))
  )
  (wire (pts (xy 135.89 196.85) (xy 124.46 196.85))
    (stroke (width 0) (type default))
  )
  (wire (pts (xy 149.86 196.85) (xy 190.5 196.85))
    (stroke (width 0) (type default))
  )
  (wire (pts (xy 237.49 184.15) (xy 226.06 184.15))
    (stroke (width 0) (type default))
  )
  (wire (pts (xy 233.68 110.49) (xy 233.68 118.11))
    (stroke (width 0) (type default))
  )
  (wire (pts (xy 251.46 161.29) (xy 262.89 161.29))
    (stroke (width 0) (type default))
  )
  (wire (pts (xy 237.49 168.91) (xy 226.06 168.91))
    (stroke (width 0) (type default))
  )
  (wire (pts (xy 251.46 120.65) (xy 262.89 120.65))
    (stroke (width 0) (type default))
  )
  (wire (pts (xy 237.49 138.43) (xy 226.06 138.43))
    (stroke (width 0) (type default))
  )
  (wire (pts (xy 135.89 95.25) (xy 133.35 95.25))
    (stroke (width 0) (type default))
  )
  (wire (pts (xy 237.49 100.33) (xy 226.06 100.33))
    (stroke (width 0) (type default))
  )
  (wire (pts (xy 237.49 80.01) (xy 226.06 80.01))
    (stroke (width 0) (type default))
  )
  (wire (pts (xy 135.89 156.21) (xy 124.46 156.21))
    (stroke (width 0) (type default))
  )
  (wire (pts (xy 149.86 128.27) (xy 161.29 128.27))
    (stroke (width 0) (type default))
  )
  (wire (pts (xy 149.86 80.01) (xy 152.4 80.01))
    (stroke (width 0) (type default))
  )
  (wire (pts (xy 251.46 107.95) (xy 262.89 107.95))
    (stroke (width 0) (type default))
  )
  (wire (pts (xy 251.46 85.09) (xy 262.89 85.09))
    (stroke (width 0) (type default))
  )
  (wire (pts (xy 251.46 146.05) (xy 262.89 146.05))
    (stroke (width 0) (type default))
  )
  (wire (pts (xy 237.49 135.89) (xy 226.06 135.89))
    (stroke (width 0) (type default))
  )
  (wire (pts (xy 251.46 123.19) (xy 262.89 123.19))
    (stroke (width 0) (type default))
  )
  (wire (pts (xy 237.49 140.97) (xy 233.68 140.97))
    (stroke (width 0) (type default))
  )
  (wire (pts (xy 237.49 130.81) (xy 226.06 130.81))
    (stroke (width 0) (type default))
  )
  (wire (pts (xy 251.46 186.69) (xy 254 186.69))
    (stroke (width 0) (type default))
  )
  (wire (pts (xy 161.29 173.99) (xy 149.86 173.99))
    (stroke (width 0) (type default))
  )
  (wire (pts (xy 161.29 151.13) (xy 149.86 151.13))
    (stroke (width 0) (type default))
  )
  (wire (pts (xy 149.86 168.91) (xy 152.4 168.91))
    (stroke (width 0) (type default))
  )
  (wire (pts (xy 135.89 128.27) (xy 124.46 128.27))
    (stroke (width 0) (type default))
  )
  (wire (pts (xy 149.86 133.35) (xy 152.4 133.35))
    (stroke (width 0) (type default))
  )
  (wire (pts (xy 149.86 186.69) (xy 149.86 189.23))
    (stroke (width 0) (type default))
  )
  (wire (pts (xy 237.49 148.59) (xy 233.68 148.59))
    (stroke (width 0) (type default))
  )
  (wire (pts (xy 237.49 95.25) (xy 233.68 95.25))
    (stroke (width 0) (type default))
  )
  (wire (pts (xy 149.86 201.93) (xy 161.29 201.93))
    (stroke (width 0) (type default))
  )
  (wire (pts (xy 135.89 146.05) (xy 124.46 146.05))
    (stroke (width 0) (type default))
  )
  (wire (pts (xy 181.61 218.44) (xy 181.61 220.98))
    (stroke (width 0) (type default))
  )
  (wire (pts (xy 149.86 191.77) (xy 161.29 191.77))
    (stroke (width 0) (type default))
  )
  (wire (pts (xy 251.46 166.37) (xy 262.89 166.37))
    (stroke (width 0) (type default))
  )
  (wire (pts (xy 149.86 105.41) (xy 157.48 105.41))
    (stroke (width 0) (type default))
  )
  (wire (pts (xy 135.89 118.11) (xy 133.35 118.11))
    (stroke (width 0) (type default))
  )
  (wire (pts (xy 135.89 102.87) (xy 124.46 102.87))
    (stroke (width 0) (type default))
  )
  (wire (pts (xy 190.5 220.98) (xy 190.5 223.52))
    (stroke (width 0) (type default))
  )
  (wire (pts (xy 135.89 130.81) (xy 133.35 130.81))
    (stroke (width 0) (type default))
  )
  (wire (pts (xy 133.35 153.67) (xy 133.35 161.29))
    (stroke (width 0) (type default))
  )
  (wire (pts (xy 135.89 120.65) (xy 124.46 120.65))
    (stroke (width 0) (type default))
  )
  (wire (pts (xy 254 125.73) (xy 254 148.59))
    (stroke (width 0) (type default))
  )
  (wire (pts (xy 251.46 191.77) (xy 262.89 191.77))
    (stroke (width 0) (type default))
  )
  (wire (pts (xy 233.68 140.97) (xy 233.68 148.59))
    (stroke (width 0) (type default))
  )
  (wire (pts (xy 149.86 194.31) (xy 161.29 194.31))
    (stroke (width 0) (type default))
  )
  (wire (pts (xy 251.46 80.01) (xy 262.89 80.01))
    (stroke (width 0) (type default))
  )
  (wire (pts (xy 237.49 87.63) (xy 233.68 87.63))
    (stroke (width 0) (type default))
  )
  (wire (pts (xy 135.89 100.33) (xy 124.46 100.33))
    (stroke (width 0) (type default))
  )
  (wire (pts (xy 237.49 123.19) (xy 226.06 123.19))
    (stroke (width 0) (type default))
  )
  (wire (pts (xy 135.89 80.01) (xy 133.35 80.01))
    (stroke (width 0) (type default))
  )
  (wire (pts (xy 149.86 123.19) (xy 161.29 123.19))
    (stroke (width 0) (type default))
  )
  (wire (pts (xy 152.4 168.91) (xy 152.4 213.36))
    (stroke (width 0) (type default))
  )
  (wire (pts (xy 152.4 87.63) (xy 152.4 95.25))
    (stroke (width 0) (type default))
  )
  (wire (pts (xy 254 156.21) (xy 254 163.83))
    (stroke (width 0) (type default))
  )
  (wire (pts (xy 251.46 133.35) (xy 262.89 133.35))
    (stroke (width 0) (type default))
  )
  (wire (pts (xy 149.86 184.15) (xy 149.86 186.69))
    (stroke (width 0) (type default))
  )
  (wire (pts (xy 254 171.45) (xy 254 179.07))
    (stroke (width 0) (type default))
  )
  (wire (pts (xy 237.49 179.07) (xy 233.68 179.07))
    (stroke (width 0) (type default))
  )
  (wire (pts (xy 133.35 105.41) (xy 133.35 118.11))
    (stroke (width 0) (type default))
  )
  (wire (pts (xy 237.49 189.23) (xy 226.06 189.23))
    (stroke (width 0) (type default))
  )
  (wire (pts (xy 251.46 105.41) (xy 262.89 105.41))
    (stroke (width 0) (type default))
  )
  (wire (pts (xy 233.68 118.11) (xy 233.68 125.73))
    (stroke (width 0) (type default))
  )
  (wire (pts (xy 135.89 199.39) (xy 124.46 199.39))
    (stroke (width 0) (type default))
  )
  (wire (pts (xy 133.35 201.93) (xy 135.89 201.93))
    (stroke (width 0) (type default))
  )
  (wire (pts (xy 251.46 158.75) (xy 262.89 158.75))
    (stroke (width 0) (type default))
  )
  (wire (pts (xy 237.49 181.61) (xy 226.06 181.61))
    (stroke (width 0) (type default))
  )
  (wire (pts (xy 149.86 92.71) (xy 161.29 92.71))
    (stroke (width 0) (type default))
  )
  (wire (pts (xy 254 110.49) (xy 254 118.11))
    (stroke (width 0) (type default))
  )
  (wire (pts (xy 254 163.83) (xy 254 171.45))
    (stroke (width 0) (type default))
  )
  (wire (pts (xy 135.89 110.49) (xy 124.46 110.49))
    (stroke (width 0) (type default))
  )
  (wire (pts (xy 135.89 184.15) (xy 135.89 186.69))
    (stroke (width 0) (type default))
  )
  (wire (pts (xy 149.86 90.17) (xy 161.29 90.17))
    (stroke (width 0) (type default))
  )
  (wire (pts (xy 251.46 110.49) (xy 254 110.49))
    (stroke (width 0) (type default))
  )
  (wire (pts (xy 149.86 148.59) (xy 161.29 148.59))
    (stroke (width 0) (type default))
  )
  (wire (pts (xy 149.86 163.83) (xy 161.29 163.83))
    (stroke (width 0) (type default))
  )
  (wire (pts (xy 254 102.87) (xy 254 110.49))
    (stroke (width 0) (type default))
  )
  (wire (pts (xy 161.29 166.37) (xy 149.86 166.37))
    (stroke (width 0) (type default))
  )
  (wire (pts (xy 251.46 163.83) (xy 254 163.83))
    (stroke (width 0) (type default))
  )
  (wire (pts (xy 254 118.11) (xy 254 125.73))
    (stroke (width 0) (type default))
  )
  (wire (pts (xy 190.5 214.63) (xy 190.5 220.98))
    (stroke (width 0) (type default))
  )
  (wire (pts (xy 233.68 102.87) (xy 233.68 110.49))
    (stroke (width 0) (type default))
  )
  (wire (pts (xy 251.46 168.91) (xy 262.89 168.91))
    (stroke (width 0) (type default))
  )
  (wire (pts (xy 251.46 100.33) (xy 262.89 100.33))
    (stroke (width 0) (type default))
  )
  (wire (pts (xy 135.89 85.09) (xy 124.46 85.09))
    (stroke (width 0) (type default))
  )
  (wire (pts (xy 254 95.25) (xy 254 102.87))
    (stroke (width 0) (type default))
  )
  (wire (pts (xy 254 186.69) (xy 254 194.31))
    (stroke (width 0) (type default))
  )
  (wire (pts (xy 181.61 220.98) (xy 190.5 220.98))
    (stroke (width 0) (type default))
  )
  (wire (pts (xy 149.86 82.55) (xy 161.29 82.55))
    (stroke (width 0) (type default))
  )
  (wire (pts (xy 251.46 130.81) (xy 262.89 130.81))
    (stroke (width 0) (type default))
  )
  (wire (pts (xy 254 194.31) (xy 254 201.93))
    (stroke (width 0) (type default))
  )
  (wire (pts (xy 237.49 120.65) (xy 226.06 120.65))
    (stroke (width 0) (type default))
  )
  (wire (pts (xy 237.49 153.67) (xy 226.06 153.67))
    (stroke (width 0) (type default))
  )
  (wire (pts (xy 251.46 179.07) (xy 254 179.07))
    (stroke (width 0) (type default))
  )
  (wire (pts (xy 133.35 80.01) (xy 133.35 87.63))
    (stroke (width 0) (type default))
  )
  (wire (pts (xy 237.49 196.85) (xy 226.06 196.85))
    (stroke (width 0) (type default))
  )
  (wire (pts (xy 251.46 128.27) (xy 262.89 128.27))
    (stroke (width 0) (type default))
  )
  (wire (pts (xy 135.89 194.31) (xy 124.46 194.31))
    (stroke (width 0) (type default))
  )
  (wire (pts (xy 237.49 186.69) (xy 233.68 186.69))
    (stroke (width 0) (type default))
  )

  (text "Raspberry CM4 connector" (at 169.418 62.992 0)
    (effects (font (size 2.54 2.54) bold) (justify left bottom))
  )

  (label "nRPi_BOOT" (at 175.26 196.85 0) (fields_autoplaced)
    (effects (font (size 1.27 1.27)) (justify left bottom))
  )

  (global_label "PSCIE_nRST" (shape input) (at 262.89 90.17 0) (fields_autoplaced)
    (effects (font (size 1.27 1.27)) (justify left))
    (property "Intersheetrefs" "${INTERSHEET_REFS}" (at 276.2813 90.0906 0)
      (effects (font (size 1.27 1.27)) (justify left) hide)
    )
  )
  (global_label "DSI0_C_N" (shape input) (at 262.89 166.37 0) (fields_autoplaced)
    (effects (font (size 1.27 1.27)) (justify left))
    (property "Intersheetrefs" "${INTERSHEET_REFS}" (at 274.0437 166.2906 0)
      (effects (font (size 1.27 1.27)) (justify left) hide)
    )
  )
  (global_label "HDMI1_D1_P" (shape input) (at 226.06 143.51 180) (fields_autoplaced)
    (effects (font (size 1.27 1.27)) (justify right))
    (property "Intersheetrefs" "${INTERSHEET_REFS}" (at 212.1848 143.4306 0)
      (effects (font (size 1.27 1.27)) (justify right) hide)
    )
  )
  (global_label "HDMI0_D0_P" (shape input) (at 226.06 181.61 180) (fields_autoplaced)
    (effects (font (size 1.27 1.27)) (justify right))
    (property "Intersheetrefs" "${INTERSHEET_REFS}" (at 212.1848 181.5306 0)
      (effects (font (size 1.27 1.27)) (justify right) hide)
    )
  )
  (global_label "DSI1_C_N" (shape input) (at 262.89 189.23 0) (fields_autoplaced)
    (effects (font (size 1.27 1.27)) (justify left))
    (property "Intersheetrefs" "${INTERSHEET_REFS}" (at 274.0437 189.1506 0)
      (effects (font (size 1.27 1.27)) (justify left) hide)
    )
  )
  (global_label "GPIO20" (shape input) (at 161.29 113.03 0) (fields_autoplaced)
    (effects (font (size 1.27 1.27)) (justify left))
    (property "Intersheetrefs" "${INTERSHEET_REFS}" (at 27.94 13.97 0)
      (effects (font (size 1.27 1.27)) hide)
    )
  )
  (global_label "HDMI1_HOTPLUG" (shape input) (at 262.89 133.35 0) (fields_autoplaced)
    (effects (font (size 1.27 1.27)) (justify left))
    (property "Intersheetrefs" "${INTERSHEET_REFS}" (at 280.5752 133.2706 0)
      (effects (font (size 1.27 1.27)) (justify left) hide)
    )
  )
  (global_label "SYNC_OUT" (shape input) (at 124.46 100.33 180) (fields_autoplaced)
    (effects (font (size 1.27 1.27)) (justify right))
    (property "Intersheetrefs" "${INTERSHEET_REFS}" (at 39.37 13.97 0)
      (effects (font (size 1.27 1.27)) hide)
    )
  )
  (global_label "GPIO22" (shape input) (at 124.46 135.89 180) (fields_autoplaced)
    (effects (font (size 1.27 1.27)) (justify right))
    (property "Intersheetrefs" "${INTERSHEET_REFS}" (at 39.37 13.97 0)
      (effects (font (size 1.27 1.27)) hide)
    )
  )
  (global_label "GPIO27" (shape input) (at 124.46 138.43 180) (fields_autoplaced)
    (effects (font (size 1.27 1.27)) (justify right))
    (property "Intersheetrefs" "${INTERSHEET_REFS}" (at 39.37 13.97 0)
      (effects (font (size 1.27 1.27)) hide)
    )
  )
  (global_label "GPIO3" (shape input) (at 124.46 148.59 180) (fields_autoplaced)
    (effects (font (size 1.27 1.27)) (justify right))
    (property "Intersheetrefs" "${INTERSHEET_REFS}" (at 39.37 13.97 0)
      (effects (font (size 1.27 1.27)) hide)
    )
  )
  (global_label "PCIE_CLK_N" (shape input) (at 226.06 92.71 180) (fields_autoplaced)
    (effects (font (size 1.27 1.27)) (justify right))
    (property "Intersheetrefs" "${INTERSHEET_REFS}" (at 212.6082 92.6306 0)
      (effects (font (size 1.27 1.27)) (justify right) hide)
    )
  )
  (global_label "nEXTRST" (shape input) (at 124.46 204.47 180) (fields_autoplaced)
    (effects (font (size 1.27 1.27)) (justify right))
    (property "Intersheetrefs" "${INTERSHEET_REFS}" (at 114.2134 204.3906 0)
      (effects (font (size 1.27 1.27)) (justify right) hide)
    )
  )
  (global_label "GPIO7" (shape input) (at 161.29 125.73 0) (fields_autoplaced)
    (effects (font (size 1.27 1.27)) (justify left))
    (property "Intersheetrefs" "${INTERSHEET_REFS}" (at 27.94 13.97 0)
      (effects (font (size 1.27 1.27)) hide)
    )
  )
  (global_label "CAM1_D2_P" (shape input) (at 262.89 123.19 0) (fields_autoplaced)
    (effects (font (size 1.27 1.27)) (justify left))
    (property "Intersheetrefs" "${INTERSHEET_REFS}" (at 275.9185 123.1106 0)
      (effects (font (size 1.27 1.27)) (justify left) hide)
    )
  )
  (global_label "PROG_MODE" (shape input) (at 167.64 210.82 180) (fields_autoplaced)
    (effects (font (size 1.27 1.27)) (justify right))
    (property "Intersheetrefs" "${INTERSHEET_REFS}" (at 154.0068 210.7406 0)
      (effects (font (size 1.27 1.27)) (justify right) hide)
    )
  )
  (global_label "CAM0_C_P" (shape input) (at 226.06 130.81 180) (fields_autoplaced)
    (effects (font (size 1.27 1.27)) (justify right))
    (property "Intersheetrefs" "${INTERSHEET_REFS}" (at 214.241 130.7306 0)
      (effects (font (size 1.27 1.27)) (justify right) hide)
    )
  )
  (global_label "PCIE_RX_P" (shape input) (at 226.06 97.79 180) (fields_autoplaced)
    (effects (font (size 1.27 1.27)) (justify right))
    (property "Intersheetrefs" "${INTERSHEET_REFS}" (at 213.7572 97.7106 0)
      (effects (font (size 1.27 1.27)) (justify right) hide)
    )
  )
  (global_label "HDMI0_D0_N" (shape input) (at 226.06 184.15 180) (fields_autoplaced)
    (effects (font (size 1.27 1.27)) (justify right))
    (property "Intersheetrefs" "${INTERSHEET_REFS}" (at 212.1244 184.0706 0)
      (effects (font (size 1.27 1.27)) (justify right) hide)
    )
  )
  (global_label "PCIE_CLK_nREQ" (shape input) (at 226.06 80.01 180) (fields_autoplaced)
    (effects (font (size 1.27 1.27)) (justify right))
    (property "Intersheetrefs" "${INTERSHEET_REFS}" (at 209.0401 79.9306 0)
      (effects (font (size 1.27 1.27)) (justify right) hide)
    )
  )
  (global_label "HDMI0_SCL" (shape input) (at 226.06 204.47 180) (fields_autoplaced)
    (effects (font (size 1.27 1.27)) (justify right))
    (property "Intersheetrefs" "${INTERSHEET_REFS}" (at 213.3944 204.3906 0)
      (effects (font (size 1.27 1.27)) (justify right) hide)
    )
  )
  (global_label "DSI1_D1_N" (shape input) (at 262.89 181.61 0) (fields_autoplaced)
    (effects (font (size 1.27 1.27)) (justify left))
    (property "Intersheetrefs" "${INTERSHEET_REFS}" (at 275.2532 181.5306 0)
      (effects (font (size 1.27 1.27)) (justify left) hide)
    )
  )
  (global_label "DSI2_D1_P" (shape input) (at 262.89 199.39 0) (fields_autoplaced)
    (effects (font (size 1.27 1.27)) (justify left))
    (property "Intersheetrefs" "${INTERSHEET_REFS}" (at 275.1928 199.3106 0)
      (effects (font (size 1.27 1.27)) (justify left) hide)
    )
  )
  (global_label "EEPROM_nWP" (shape input) (at 124.46 102.87 180) (fields_autoplaced)
    (effects (font (size 1.27 1.27)) (justify right))
    (property "Intersheetrefs" "${INTERSHEET_REFS}" (at 39.37 13.97 0)
      (effects (font (size 1.27 1.27)) hide)
    )
  )
  (global_label "VCC5V0" (shape input) (at 161.29 181.61 0) (fields_autoplaced)
    (effects (font (size 1.27 1.27)) (justify left))
    (property "Intersheetrefs" "${INTERSHEET_REFS}" (at 170.7504 181.5306 0)
      (effects (font (size 1.27 1.27)) (justify left) hide)
    )
  )
  (global_label "TRD0_N" (shape input) (at 124.46 90.17 180) (fields_autoplaced)
    (effects (font (size 1.27 1.27)) (justify right))
    (property "Intersheetrefs" "${INTERSHEET_REFS}" (at 39.37 13.97 0)
      (effects (font (size 1.27 1.27)) hide)
    )
  )
  (global_label "GPIO8" (shape input) (at 161.29 128.27 0) (fields_autoplaced)
    (effects (font (size 1.27 1.27)) (justify left))
    (property "Intersheetrefs" "${INTERSHEET_REFS}" (at 27.94 13.97 0)
      (effects (font (size 1.27 1.27)) hide)
    )
  )
  (global_label "CAM_GPIO" (shape input) (at 161.29 201.93 0) (fields_autoplaced)
    (effects (font (size 1.27 1.27)) (justify left))
    (property "Intersheetrefs" "${INTERSHEET_REFS}" (at 172.8671 201.8506 0)
      (effects (font (size 1.27 1.27)) (justify left) hide)
    )
  )
  (global_label "CAM0_C_N" (shape input) (at 226.06 128.27 180) (fields_autoplaced)
    (effects (font (size 1.27 1.27)) (justify right))
    (property "Intersheetrefs" "${INTERSHEET_REFS}" (at 214.1806 128.1906 0)
      (effects (font (size 1.27 1.27)) (justify right) hide)
    )
  )
  (global_label "VCC1V8" (shape input) (at 124.46 189.23 180) (fields_autoplaced)
    (effects (font (size 1.27 1.27)) (justify right))
    (property "Intersheetrefs" "${INTERSHEET_REFS}" (at 114.9996 189.1506 0)
      (effects (font (size 1.27 1.27)) (justify right) hide)
    )
  )
  (global_label "HDMI1_D0_P" (shape input) (at 226.06 151.13 180) (fields_autoplaced)
    (effects (font (size 1.27 1.27)) (justify right))
    (property "Intersheetrefs" "${INTERSHEET_REFS}" (at 212.1848 151.0506 0)
      (effects (font (size 1.27 1.27)) (justify right) hide)
    )
  )
  (global_label "GPIO16" (shape input) (at 161.29 115.57 0) (fields_autoplaced)
    (effects (font (size 1.27 1.27)) (justify left))
    (property "Intersheetrefs" "${INTERSHEET_REFS}" (at 27.94 13.97 0)
      (effects (font (size 1.27 1.27)) hide)
    )
  )
  (global_label "GPIO19" (shape input) (at 124.46 110.49 180) (fields_autoplaced)
    (effects (font (size 1.27 1.27)) (justify right))
    (property "Intersheetrefs" "${INTERSHEET_REFS}" (at 39.37 13.97 0)
      (effects (font (size 1.27 1.27)) hide)
    )
  )
  (global_label "HDMI1_D0_N" (shape input) (at 226.06 153.67 180) (fields_autoplaced)
    (effects (font (size 1.27 1.27)) (justify right))
    (property "Intersheetrefs" "${INTERSHEET_REFS}" (at 212.1244 153.5906 0)
      (effects (font (size 1.27 1.27)) (justify right) hide)
    )
  )
  (global_label "CAM0_D1_P" (shape input) (at 226.06 123.19 180) (fields_autoplaced)
    (effects (font (size 1.27 1.27)) (justify right))
    (property "Intersheetrefs" "${INTERSHEET_REFS}" (at 213.0315 123.1106 0)
      (effects (font (size 1.27 1.27)) (justify right) hide)
    )
  )
  (global_label "RPi_TXD" (shape output) (at 161.29 148.59 0) (fields_autoplaced)
    (effects (font (size 1.27 1.27)) (justify left))
    (property "Intersheetrefs" "${INTERSHEET_REFS}" (at 27.94 13.97 0)
      (effects (font (size 1.27 1.27)) hide)
    )
  )
  (global_label "RESERVED" (shape input) (at 124.46 173.99 180) (fields_autoplaced)
    (effects (font (size 1.27 1.27)) (justify right))
    (property "Intersheetrefs" "${INTERSHEET_REFS}" (at 112.5806 173.9106 0)
      (effects (font (size 1.27 1.27)) (justify right) hide)
    )
  )
  (global_label "PCIE_RX_N" (shape input) (at 226.06 100.33 180) (fields_autoplaced)
    (effects (font (size 1.27 1.27)) (justify right))
    (property "Intersheetrefs" "${INTERSHEET_REFS}" (at 213.6968 100.2506 0)
      (effects (font (size 1.27 1.27)) (justify right) hide)
    )
  )
  (global_label "CAM0_D1_N" (shape input) (at 226.06 120.65 180) (fields_autoplaced)
    (effects (font (size 1.27 1.27)) (justify right))
    (property "Intersheetrefs" "${INTERSHEET_REFS}" (at 212.971 120.5706 0)
      (effects (font (size 1.27 1.27)) (justify right) hide)
    )
  )
  (global_label "PCIE_TX_P" (shape input) (at 226.06 105.41 180) (fields_autoplaced)
    (effects (font (size 1.27 1.27)) (justify right))
    (property "Intersheetrefs" "${INTERSHEET_REFS}" (at 214.0596 105.3306 0)
      (effects (font (size 1.27 1.27)) (justify right) hide)
    )
  )
  (global_label "DSI1_C_P" (shape input) (at 262.89 191.77 0) (fields_autoplaced)
    (effects (font (size 1.27 1.27)) (justify left))
    (property "Intersheetrefs" "${INTERSHEET_REFS}" (at 273.9832 191.6906 0)
      (effects (font (size 1.27 1.27)) (justify left) hide)
    )
  )
  (global_label "HDMI1_CEC" (shape input) (at 262.89 140.97 0) (fields_autoplaced)
    (effects (font (size 1.27 1.27)) (justify left))
    (property "Intersheetrefs" "${INTERSHEET_REFS}" (at 275.7371 140.8906 0)
      (effects (font (size 1.27 1.27)) (justify left) hide)
    )
  )
  (global_label "SD_CMD" (shape input) (at 124.46 156.21 180) (fields_autoplaced)
    (effects (font (size 1.27 1.27)) (justify right))
    (property "Intersheetrefs" "${INTERSHEET_REFS}" (at 114.6972 156.1306 0)
      (effects (font (size 1.27 1.27)) (justify right) hide)
    )
  )
  (global_label "SD_DAT2" (shape input) (at 161.29 166.37 0) (fields_autoplaced)
    (effects (font (size 1.27 1.27)) (justify left))
    (property "Intersheetrefs" "${INTERSHEET_REFS}" (at 171.5971 166.2906 0)
      (effects (font (size 1.27 1.27)) (justify left) hide)
    )
  )
  (global_label "TRD1_P" (shape input) (at 124.46 82.55 180) (fields_autoplaced)
    (effects (font (size 1.27 1.27)) (justify right))
    (property "Intersheetrefs" "${INTERSHEET_REFS}" (at 39.37 13.97 0)
      (effects (font (size 1.27 1.27)) hide)
    )
  )
  (global_label "CAM1_C_P" (shape input) (at 262.89 115.57 0) (fields_autoplaced)
    (effects (font (size 1.27 1.27)) (justify left))
    (property "Intersheetrefs" "${INTERSHEET_REFS}" (at 274.709 115.4906 0)
      (effects (font (size 1.27 1.27)) (justify left) hide)
    )
  )
  (global_label "HDMI0_CK_P" (shape input) (at 226.06 189.23 180) (fields_autoplaced)
    (effects (font (size 1.27 1.27)) (justify right))
    (property "Intersheetrefs" "${INTERSHEET_REFS}" (at 212.1244 189.1506 0)
      (effects (font (size 1.27 1.27)) (justify right) hide)
    )
  )
  (global_label "GPIO5" (shape input) (at 124.46 120.65 180) (fields_autoplaced)
    (effects (font (size 1.27 1.27)) (justify right))
    (property "Intersheetrefs" "${INTERSHEET_REFS}" (at 39.37 13.97 0)
      (effects (font (size 1.27 1.27)) hide)
    )
  )
  (global_label "DSI2_D1_N" (shape input) (at 262.89 196.85 0) (fields_autoplaced)
    (effects (font (size 1.27 1.27)) (justify left))
    (property "Intersheetrefs" "${INTERSHEET_REFS}" (at 275.2532 196.7706 0)
      (effects (font (size 1.27 1.27)) (justify left) hide)
    )
  )
  (global_label "HDMI0_D1_P" (shape input) (at 226.06 173.99 180) (fields_autoplaced)
    (effects (font (size 1.27 1.27)) (justify right))
    (property "Intersheetrefs" "${INTERSHEET_REFS}" (at 212.1848 173.9106 0)
      (effects (font (size 1.27 1.27)) (justify right) hide)
    )
  )
  (global_label "SD_DAT1" (shape input) (at 161.29 163.83 0) (fields_autoplaced)
    (effects (font (size 1.27 1.27)) (justify left))
    (property "Intersheetrefs" "${INTERSHEET_REFS}" (at 171.5971 163.7506 0)
      (effects (font (size 1.27 1.27)) (justify left) hide)
    )
  )
  (global_label "GPIO4" (shape input) (at 124.46 146.05 180) (fields_autoplaced)
    (effects (font (size 1.27 1.27)) (justify right))
    (property "Intersheetrefs" "${INTERSHEET_REFS}" (at 39.37 13.97 0)
      (effects (font (size 1.27 1.27)) hide)
    )
  )
  (global_label "HDMI1_CK_N" (shape input) (at 226.06 161.29 180) (fields_autoplaced)
    (effects (font (size 1.27 1.27)) (justify right))
    (property "Intersheetrefs" "${INTERSHEET_REFS}" (at 212.0639 161.2106 0)
      (effects (font (size 1.27 1.27)) (justify right) hide)
    )
  )
  (global_label "HDMI0_HOTPLUG" (shape input) (at 262.89 146.05 0) (fields_autoplaced)
    (effects (font (size 1.27 1.27)) (justify left))
    (property "Intersheetrefs" "${INTERSHEET_REFS}" (at 280.5752 145.9706 0)
      (effects (font (size 1.27 1.27)) (justify left) hide)
    )
  )
  (global_label "HDMI0_D1_N" (shape input) (at 226.06 176.53 180) (fields_autoplaced)
    (effects (font (size 1.27 1.27)) (justify right))
    (property "Intersheetrefs" "${INTERSHEET_REFS}" (at 212.1244 176.4506 0)
      (effects (font (size 1.27 1.27)) (justify right) hide)
    )
  )
  (global_label "TRD3_N" (shape input) (at 161.29 85.09 0) (fields_autoplaced)
    (effects (font (size 1.27 1.27)) (justify left))
    (property "Intersheetrefs" "${INTERSHEET_REFS}" (at 27.94 13.97 0)
      (effects (font (size 1.27 1.27)) hide)
    )
  )
  (global_label "USB2_P" (shape input) (at 262.89 85.09 0) (fields_autoplaced)
    (effects (font (size 1.27 1.27)) (justify left))
    (property "Intersheetrefs" "${INTERSHEET_REFS}" (at 272.4713 85.0106 0)
      (effects (font (size 1.27 1.27)) (justify left) hide)
    )
  )
  (global_label "CAM1_C_N" (shape input) (at 262.89 113.03 0) (fields_autoplaced)
    (effects (font (size 1.27 1.27)) (justify left))
    (property "Intersheetrefs" "${INTERSHEET_REFS}" (at 274.7694 112.9506 0)
      (effects (font (size 1.27 1.27)) (justify left) hide)
    )
  )
  (global_label "GPIO9" (shape input) (at 124.46 128.27 180) (fields_autoplaced)
    (effects (font (size 1.27 1.27)) (justify right))
    (property "Intersheetrefs" "${INTERSHEET_REFS}" (at 39.37 13.97 0)
      (effects (font (size 1.27 1.27)) hide)
    )
  )
  (global_label "HDMI1_SCL" (shape input) (at 262.89 138.43 0) (fields_autoplaced)
    (effects (font (size 1.27 1.27)) (justify left))
    (property "Intersheetrefs" "${INTERSHEET_REFS}" (at 275.5556 138.3506 0)
      (effects (font (size 1.27 1.27)) (justify left) hide)
    )
  )
  (global_label "ETH_LEDY" (shape input) (at 161.29 100.33 0) (fields_autoplaced)
    (effects (font (size 1.27 1.27)) (justify left))
    (property "Intersheetrefs" "${INTERSHEET_REFS}" (at 27.94 13.97 0)
      (effects (font (size 1.27 1.27)) hide)
    )
  )
  (global_label "TRD3_P" (shape input) (at 161.29 82.55 0) (fields_autoplaced)
    (effects (font (size 1.27 1.27)) (justify left))
    (property "Intersheetrefs" "${INTERSHEET_REFS}" (at 27.94 13.97 0)
      (effects (font (size 1.27 1.27)) hide)
    )
  )
  (global_label "GPIO2" (shape input) (at 124.46 151.13 180) (fields_autoplaced)
    (effects (font (size 1.27 1.27)) (justify right))
    (property "Intersheetrefs" "${INTERSHEET_REFS}" (at 116.451 151.0506 0)
      (effects (font (size 1.27 1.27)) (justify right) hide)
    )
  )
  (global_label "DSI1_D3_N" (shape input) (at 226.06 196.85 180) (fields_autoplaced)
    (effects (font (size 1.27 1.27)) (justify right))
    (property "Intersheetrefs" "${INTERSHEET_REFS}" (at 213.6968 196.7706 0)
      (effects (font (size 1.27 1.27)) (justify right) hide)
    )
  )
  (global_label "ETH_LEDG" (shape input) (at 161.29 97.79 0) (fields_autoplaced)
    (effects (font (size 1.27 1.27)) (justify left))
    (property "Intersheetrefs" "${INTERSHEET_REFS}" (at 27.94 13.97 0)
      (effects (font (size 1.27 1.27)) hide)
    )
  )
  (global_label "TV_OUT" (shape input) (at 262.89 92.71 0) (fields_autoplaced)
    (effects (font (size 1.27 1.27)) (justify left))
    (property "Intersheetrefs" "${INTERSHEET_REFS}" (at 271.8666 92.6306 0)
      (effects (font (size 1.27 1.27)) (justify left) hide)
    )
  )
  (global_label "DSI1_D1_P" (shape input) (at 262.89 184.15 0) (fields_autoplaced)
    (effects (font (size 1.27 1.27)) (justify left))
    (property "Intersheetrefs" "${INTERSHEET_REFS}" (at 275.1928 184.0706 0)
      (effects (font (size 1.27 1.27)) (justify left) hide)
    )
  )
  (global_label "SD_DAT3" (shape input) (at 161.29 156.21 0) (fields_autoplaced)
    (effects (font (size 1.27 1.27)) (justify left))
    (property "Intersheetrefs" "${INTERSHEET_REFS}" (at 171.5971 156.1306 0)
      (effects (font (size 1.27 1.27)) (justify left) hide)
    )
  )
  (global_label "HDMI0_SDA" (shape input) (at 262.89 204.47 0) (fields_autoplaced)
    (effects (font (size 1.27 1.27)) (justify left))
    (property "Intersheetrefs" "${INTERSHEET_REFS}" (at 275.6161 204.3906 0)
      (effects (font (size 1.27 1.27)) (justify left) hide)
    )
  )
  (global_label "HDMI0_D2_P" (shape input) (at 226.06 166.37 180) (fields_autoplaced)
    (effects (font (size 1.27 1.27)) (justify right))
    (property "Intersheetrefs" "${INTERSHEET_REFS}" (at 212.1848 166.2906 0)
      (effects (font (size 1.27 1.27)) (justify right) hide)
    )
  )
  (global_label "nPWR_LED" (shape input) (at 161.29 199.39 0) (fields_autoplaced)
    (effects (font (size 1.27 1.27)) (justify left))
    (property "Intersheetrefs" "${INTERSHEET_REFS}" (at 173.1694 199.3106 0)
      (effects (font (size 1.27 1.27)) (justify left) hide)
    )
  )
  (global_label "SD_DAT0" (shape input) (at 161.29 158.75 0) (fields_autoplaced)
    (effects (font (size 1.27 1.27)) (justify left))
    (property "Intersheetrefs" "${INTERSHEET_REFS}" (at 171.5971 158.6706 0)
      (effects (font (size 1.27 1.27)) (justify left) hide)
    )
  )
  (global_label "GPIO24" (shape input) (at 161.29 135.89 0) (fields_autoplaced)
    (effects (font (size 1.27 1.27)) (justify left))
    (property "Intersheetrefs" "${INTERSHEET_REFS}" (at 27.94 13.97 0)
      (effects (font (size 1.27 1.27)) hide)
    )
  )
  (global_label "GPIO26" (shape input) (at 124.46 107.95 180) (fields_autoplaced)
    (effects (font (size 1.27 1.27)) (justify right))
    (property "Intersheetrefs" "${INTERSHEET_REFS}" (at 39.37 13.97 0)
      (effects (font (size 1.27 1.27)) hide)
    )
  )
  (global_label "USB2_N" (shape input) (at 262.89 82.55 0) (fields_autoplaced)
    (effects (font (size 1.27 1.27)) (justify left))
    (property "Intersheetrefs" "${INTERSHEET_REFS}" (at 272.5318 82.4706 0)
      (effects (font (size 1.27 1.27)) (justify left) hide)
    )
  )
  (global_label "HDMI0_D2_N" (shape input) (at 226.06 168.91 180) (fields_autoplaced)
    (effects (font (size 1.27 1.27)) (justify right))
    (property "Intersheetrefs" "${INTERSHEET_REFS}" (at 212.1244 168.8306 0)
      (effects (font (size 1.27 1.27)) (justify right) hide)
    )
  )
  (global_label "CAM1_D0_P" (shape input) (at 262.89 100.33 0) (fields_autoplaced)
    (effects (font (size 1.27 1.27)) (justify left))
    (property "Intersheetrefs" "${INTERSHEET_REFS}" (at 275.9185 100.2506 0)
      (effects (font (size 1.27 1.27)) (justify left) hide)
    )
  )
  (global_label "HDMI1_D1_N" (shape input) (at 226.06 146.05 180) (fields_autoplaced)
    (effects (font (size 1.27 1.27)) (justify right))
    (property "Intersheetrefs" "${INTERSHEET_REFS}" (at 212.1244 145.9706 0)
      (effects (font (size 1.27 1.27)) (justify right) hide)
    )
  )
  (global_label "USBOTG_ID" (shape input) (at 262.89 80.01 0) (fields_autoplaced)
    (effects (font (size 1.27 1.27)) (justify left))
    (property "Intersheetrefs" "${INTERSHEET_REFS}" (at 275.4347 79.9306 0)
      (effects (font (size 1.27 1.27)) (justify left) hide)
    )
  )
  (global_label "BT_nDis" (shape input) (at 161.29 194.31 0) (fields_autoplaced)
    (effects (font (size 1.27 1.27)) (justify left))
    (property "Intersheetrefs" "${INTERSHEET_REFS}" (at 170.8713 194.2306 0)
      (effects (font (size 1.27 1.27)) (justify left) hide)
    )
  )
  (global_label "AIN1" (shape input) (at 124.46 196.85 180) (fields_autoplaced)
    (effects (font (size 1.27 1.27)) (justify right))
    (property "Intersheetrefs" "${INTERSHEET_REFS}" (at 117.9025 196.7706 0)
      (effects (font (size 1.27 1.27)) (justify right) hide)
    )
  )
  (global_label "DSI1_D0_P" (shape input) (at 262.89 176.53 0) (fields_autoplaced)
    (effects (font (size 1.27 1.27)) (justify left))
    (property "Intersheetrefs" "${INTERSHEET_REFS}" (at 275.1928 176.4506 0)
      (effects (font (size 1.27 1.27)) (justify left) hide)
    )
  )
  (global_label "RPi_RXD" (shape input) (at 161.29 143.51 0) (fields_autoplaced)
    (effects (font (size 1.27 1.27)) (justify left))
    (property "Intersheetrefs" "${INTERSHEET_REFS}" (at 27.94 13.97 0)
      (effects (font (size 1.27 1.27)) hide)
    )
  )
  (global_label "TRD2_P" (shape input) (at 161.29 92.71 0) (fields_autoplaced)
    (effects (font (size 1.27 1.27)) (justify left))
    (property "Intersheetrefs" "${INTERSHEET_REFS}" (at 27.94 13.97 0)
      (effects (font (size 1.27 1.27)) hide)
    )
  )
  (global_label "GPIO25" (shape input) (at 161.29 130.81 0) (fields_autoplaced)
    (effects (font (size 1.27 1.27)) (justify left))
    (property "Intersheetrefs" "${INTERSHEET_REFS}" (at 27.94 13.97 0)
      (effects (font (size 1.27 1.27)) hide)
    )
  )
  (global_label "TRD0_P" (shape input) (at 124.46 92.71 180) (fields_autoplaced)
    (effects (font (size 1.27 1.27)) (justify right))
    (property "Intersheetrefs" "${INTERSHEET_REFS}" (at 39.37 13.97 0)
      (effects (font (size 1.27 1.27)) hide)
    )
  )
  (global_label "SD_PWR_ON" (shape input) (at 161.29 173.99 0) (fields_autoplaced)
    (effects (font (size 1.27 1.27)) (justify left))
    (property "Intersheetrefs" "${INTERSHEET_REFS}" (at 174.6813 173.9106 0)
      (effects (font (size 1.27 1.27)) (justify left) hide)
    )
  )
  (global_label "DSI0_D1_P" (shape input) (at 262.89 161.29 0) (fields_autoplaced)
    (effects (font (size 1.27 1.27)) (justify left))
    (property "Intersheetrefs" "${INTERSHEET_REFS}" (at 275.1928 161.2106 0)
      (effects (font (size 1.27 1.27)) (justify left) hide)
    )
  )
  (global_label "RUN_PG" (shape input) (at 124.46 194.31 180) (fields_autoplaced)
    (effects (font (size 1.27 1.27)) (justify right))
    (property "Intersheetrefs" "${INTERSHEET_REFS}" (at 114.6972 194.2306 0)
      (effects (font (size 1.27 1.27)) (justify right) hide)
    )
  )
  (global_label "3V3_RPi" (shape input) (at 177.8 93.98 90) (fields_autoplaced)
    (effects (font (size 1.27 1.27)) (justify left))
    (property "Intersheetrefs" "${INTERSHEET_REFS}" (at 29.21 13.97 0)
      (effects (font (size 1.27 1.27)) hide)
    )
  )
  (global_label "CAM1_D2_N" (shape input) (at 262.89 120.65 0) (fields_autoplaced)
    (effects (font (size 1.27 1.27)) (justify left))
    (property "Intersheetrefs" "${INTERSHEET_REFS}" (at 275.979 120.5706 0)
      (effects (font (size 1.27 1.27)) (justify left) hide)
    )
  )
  (global_label "AIN0" (shape input) (at 124.46 199.39 180) (fields_autoplaced)
    (effects (font (size 1.27 1.27)) (justify right))
    (property "Intersheetrefs" "${INTERSHEET_REFS}" (at 117.9025 199.3106 0)
      (effects (font (size 1.27 1.27)) (justify right) hide)
    )
  )
  (global_label "CAM1_D1_P" (shape input) (at 262.89 107.95 0) (fields_autoplaced)
    (effects (font (size 1.27 1.27)) (justify left))
    (property "Intersheetrefs" "${INTERSHEET_REFS}" (at 275.9185 107.8706 0)
      (effects (font (size 1.27 1.27)) (justify left) hide)
    )
  )
  (global_label "3V3_RPi" (shape input) (at 124.46 186.69 180) (fields_autoplaced)
    (effects (font (size 1.27 1.27)) (justify right))
    (property "Intersheetrefs" "${INTERSHEET_REFS}" (at 114.5158 186.6106 0)
      (effects (font (size 1.27 1.27)) (justify right) hide)
    )
  )
  (global_label "CAM1_D3_P" (shape input) (at 262.89 130.81 0) (fields_autoplaced)
    (effects (font (size 1.27 1.27)) (justify left))
    (property "Intersheetrefs" "${INTERSHEET_REFS}" (at 275.9185 130.7306 0)
      (effects (font (size 1.27 1.27)) (justify left) hide)
    )
  )
  (global_label "CAM1_D1_N" (shape input) (at 262.89 105.41 0) (fields_autoplaced)
    (effects (font (size 1.27 1.27)) (justify left))
    (property "Intersheetrefs" "${INTERSHEET_REFS}" (at 275.979 105.3306 0)
      (effects (font (size 1.27 1.27)) (justify left) hide)
    )
  )
  (global_label "GPIO18" (shape input) (at 161.29 140.97 0) (fields_autoplaced)
    (effects (font (size 1.27 1.27)) (justify left))
    (property "Intersheetrefs" "${INTERSHEET_REFS}" (at 27.94 13.97 0)
      (effects (font (size 1.27 1.27)) hide)
    )
  )
  (global_label "DSI1_D3_P" (shape input) (at 226.06 199.39 180) (fields_autoplaced)
    (effects (font (size 1.27 1.27)) (justify right))
    (property "Intersheetrefs" "${INTERSHEET_REFS}" (at 213.7572 199.3106 0)
      (effects (font (size 1.27 1.27)) (justify right) hide)
    )
  )
  (global_label "GPIO12" (shape input) (at 161.29 118.11 0) (fields_autoplaced)
    (effects (font (size 1.27 1.27)) (justify left))
    (property "Intersheetrefs" "${INTERSHEET_REFS}" (at 27.94 13.97 0)
      (effects (font (size 1.27 1.27)) hide)
    )
  )
  (global_label "DSI0_D1_N" (shape input) (at 262.89 158.75 0) (fields_autoplaced)
    (effects (font (size 1.27 1.27)) (justify left))
    (property "Intersheetrefs" "${INTERSHEET_REFS}" (at 275.2532 158.6706 0)
      (effects (font (size 1.27 1.27)) (justify left) hide)
    )
  )
  (global_label "CAM1_D0_N" (shape input) (at 262.89 97.79 0) (fields_autoplaced)
    (effects (font (size 1.27 1.27)) (justify left))
    (property "Intersheetrefs" "${INTERSHEET_REFS}" (at 275.979 97.7106 0)
      (effects (font (size 1.27 1.27)) (justify left) hide)
    )
  )
  (global_label "HDMI1_D2_P" (shape input) (at 226.06 135.89 180) (fields_autoplaced)
    (effects (font (size 1.27 1.27)) (justify right))
    (property "Intersheetrefs" "${INTERSHEET_REFS}" (at 212.1848 135.8106 0)
      (effects (font (size 1.27 1.27)) (justify right) hide)
    )
  )
  (global_label "3V3_RPi" (shape input) (at 124.46 176.53 180) (fields_autoplaced)
    (effects (font (size 1.27 1.27)) (justify right))
    (property "Intersheetrefs" "${INTERSHEET_REFS}" (at 114.5158 176.4506 0)
      (effects (font (size 1.27 1.27)) (justify right) hide)
    )
  )
  (global_label "SCL0" (shape input) (at 124.46 179.07 180) (fields_autoplaced)
    (effects (font (size 1.27 1.27)) (justify right))
    (property "Intersheetrefs" "${INTERSHEET_REFS}" (at 117.4187 178.9906 0)
      (effects (font (size 1.27 1.27)) (justify right) hide)
    )
  )
  (global_label "DSI0_D0_P" (shape input) (at 262.89 153.67 0) (fields_autoplaced)
    (effects (font (size 1.27 1.27)) (justify left))
    (property "Intersheetrefs" "${INTERSHEET_REFS}" (at 275.1928 153.5906 0)
      (effects (font (size 1.27 1.27)) (justify left) hide)
    )
  )
  (global_label "ID_SD" (shape input) (at 124.46 123.19 180) (fields_autoplaced)
    (effects (font (size 1.27 1.27)) (justify right))
    (property "Intersheetrefs" "${INTERSHEET_REFS}" (at 39.37 13.97 0)
      (effects (font (size 1.27 1.27)) hide)
    )
  )
  (global_label "CAM1_D3_N" (shape input) (at 262.89 128.27 0) (fields_autoplaced)
    (effects (font (size 1.27 1.27)) (justify left))
    (property "Intersheetrefs" "${INTERSHEET_REFS}" (at 275.979 128.1906 0)
      (effects (font (size 1.27 1.27)) (justify left) hide)
    )
  )
  (global_label "WL_nDis" (shape input) (at 161.29 191.77 0) (fields_autoplaced)
    (effects (font (size 1.27 1.27)) (justify left))
    (property "Intersheetrefs" "${INTERSHEET_REFS}" (at 171.1132 191.6906 0)
      (effects (font (size 1.27 1.27)) (justify left) hide)
    )
  )
  (global_label "HDMI1_SDA" (shape input) (at 262.89 135.89 0) (fields_autoplaced)
    (effects (font (size 1.27 1.27)) (justify left))
    (property "Intersheetrefs" "${INTERSHEET_REFS}" (at 275.6161 135.8106 0)
      (effects (font (size 1.27 1.27)) (justify left) hide)
    )
  )
  (global_label "ID_SC" (shape input) (at 161.29 123.19 0) (fields_autoplaced)
    (effects (font (size 1.27 1.27)) (justify left))
    (property "Intersheetrefs" "${INTERSHEET_REFS}" (at 27.94 13.97 0)
      (effects (font (size 1.27 1.27)) hide)
    )
  )
  (global_label "SDA0" (shape input) (at 124.46 181.61 180) (fields_autoplaced)
    (effects (font (size 1.27 1.27)) (justify right))
    (property "Intersheetrefs" "${INTERSHEET_REFS}" (at 117.3582 181.5306 0)
      (effects (font (size 1.27 1.27)) (justify right) hide)
    )
  )
  (global_label "CAM0_D0_N" (shape input) (at 226.06 113.03 180) (fields_autoplaced)
    (effects (font (size 1.27 1.27)) (justify right))
    (property "Intersheetrefs" "${INTERSHEET_REFS}" (at 212.971 112.9506 0)
      (effects (font (size 1.27 1.27)) (justify right) hide)
    )
  )
  (global_label "CAM0_D0_P" (shape input) (at 226.06 115.57 180) (fields_autoplaced)
    (effects (font (size 1.27 1.27)) (justify right))
    (property "Intersheetrefs" "${INTERSHEET_REFS}" (at 213.0315 115.4906 0)
      (effects (font (size 1.27 1.27)) (justify right) hide)
    )
  )
  (global_label "GPIO23" (shape input) (at 161.29 138.43 0) (fields_autoplaced)
    (effects (font (size 1.27 1.27)) (justify left))
    (property "Intersheetrefs" "${INTERSHEET_REFS}" (at 27.94 13.97 0)
      (effects (font (size 1.27 1.27)) hide)
    )
  )
  (global_label "SD_CLK" (shape input) (at 161.29 151.13 0) (fields_autoplaced)
    (effects (font (size 1.27 1.27)) (justify left))
    (property "Intersheetrefs" "${INTERSHEET_REFS}" (at 170.6294 151.0506 0)
      (effects (font (size 1.27 1.27)) (justify left) hide)
    )
  )
  (global_label "GPIO13" (shape input) (at 124.46 113.03 180) (fields_autoplaced)
    (effects (font (size 1.27 1.27)) (justify right))
    (property "Intersheetrefs" "${INTERSHEET_REFS}" (at 39.37 13.97 0)
      (effects (font (size 1.27 1.27)) hide)
    )
  )
  (global_label "HDMI0_CEC" (shape input) (at 262.89 143.51 0) (fields_autoplaced)
    (effects (font (size 1.27 1.27)) (justify left))
    (property "Intersheetrefs" "${INTERSHEET_REFS}" (at 275.7371 143.4306 0)
      (effects (font (size 1.27 1.27)) (justify left) hide)
    )
  )
  (global_label "DSI1_D0_N" (shape bidirectional) (at 262.89 173.99 0) (fields_autoplaced)
    (effects (font (size 1.27 1.27)) (justify left))
    (property "Intersheetrefs" "${INTERSHEET_REFS}" (at 275.2532 173.9106 0)
      (effects (font (size 1.27 1.27)) (justify left) hide)
    )
  )
  (global_label "DSI0_C_P" (shape input) (at 262.89 168.91 0) (fields_autoplaced)
    (effects (font (size 1.27 1.27)) (justify left))
    (property "Intersheetrefs" "${INTERSHEET_REFS}" (at 273.9832 168.8306 0)
      (effects (font (size 1.27 1.27)) (justify left) hide)
    )
  )
  (global_label "GLOBAL_EN" (shape input) (at 161.29 204.47 0) (fields_autoplaced)
    (effects (font (size 1.27 1.27)) (justify left))
    (property "Intersheetrefs" "${INTERSHEET_REFS}" (at 174.0766 204.3906 0)
      (effects (font (size 1.27 1.27)) (justify left) hide)
    )
  )
  (global_label "GPIO6" (shape input) (at 124.46 115.57 180) (fields_autoplaced)
    (effects (font (size 1.27 1.27)) (justify right))
    (property "Intersheetrefs" "${INTERSHEET_REFS}" (at 39.37 13.97 0)
      (effects (font (size 1.27 1.27)) hide)
    )
  )
  (global_label "PCIE_CLK_P" (shape input) (at 226.06 90.17 180) (fields_autoplaced)
    (effects (font (size 1.27 1.27)) (justify right))
    (property "Intersheetrefs" "${INTERSHEET_REFS}" (at 212.6687 90.0906 0)
      (effects (font (size 1.27 1.27)) (justify right) hide)
    )
  )
  (global_label "TRD1_N" (shape input) (at 124.46 85.09 180) (fields_autoplaced)
    (effects (font (size 1.27 1.27)) (justify right))
    (property "Intersheetrefs" "${INTERSHEET_REFS}" (at 39.37 13.97 0)
      (effects (font (size 1.27 1.27)) hide)
    )
  )
  (global_label "GPIO10" (shape input) (at 124.46 133.35 180) (fields_autoplaced)
    (effects (font (size 1.27 1.27)) (justify right))
    (property "Intersheetrefs" "${INTERSHEET_REFS}" (at 39.37 13.97 0)
      (effects (font (size 1.27 1.27)) hide)
    )
  )
  (global_label "SYNC_IN" (shape input) (at 124.46 97.79 180) (fields_autoplaced)
    (effects (font (size 1.27 1.27)) (justify right))
    (property "Intersheetrefs" "${INTERSHEET_REFS}" (at 39.37 13.97 0)
      (effects (font (size 1.27 1.27)) hide)
    )
  )
  (global_label "GPIO17" (shape input) (at 124.46 140.97 180) (fields_autoplaced)
    (effects (font (size 1.27 1.27)) (justify right))
    (property "Intersheetrefs" "${INTERSHEET_REFS}" (at 39.37 13.97 0)
      (effects (font (size 1.27 1.27)) hide)
    )
  )
  (global_label "PCIE_TX_N" (shape input) (at 226.06 107.95 180) (fields_autoplaced)
    (effects (font (size 1.27 1.27)) (justify right))
    (property "Intersheetrefs" "${INTERSHEET_REFS}" (at 213.9991 107.8706 0)
      (effects (font (size 1.27 1.27)) (justify right) hide)
    )
  )
  (global_label "GPIO21" (shape input) (at 161.29 110.49 0) (fields_autoplaced)
    (effects (font (size 1.27 1.27)) (justify left))
    (property "Intersheetrefs" "${INTERSHEET_REFS}" (at 27.94 13.97 0)
      (effects (font (size 1.27 1.27)) hide)
    )
  )
  (global_label "GPIO11" (shape input) (at 124.46 125.73 180) (fields_autoplaced)
    (effects (font (size 1.27 1.27)) (justify right))
    (property "Intersheetrefs" "${INTERSHEET_REFS}" (at 39.37 13.97 0)
      (effects (font (size 1.27 1.27)) hide)
    )
  )
  (global_label "HDMI1_CK_P" (shape input) (at 226.06 158.75 180) (fields_autoplaced)
    (effects (font (size 1.27 1.27)) (justify right))
    (property "Intersheetrefs" "${INTERSHEET_REFS}" (at 212.1244 158.6706 0)
      (effects (font (size 1.27 1.27)) (justify right) hide)
    )
  )
  (global_label "HDMI1_D2_N" (shape input) (at 226.06 138.43 180) (fields_autoplaced)
    (effects (font (size 1.27 1.27)) (justify right))
    (property "Intersheetrefs" "${INTERSHEET_REFS}" (at 212.1244 138.3506 0)
      (effects (font (size 1.27 1.27)) (justify right) hide)
    )
  )
  (global_label "HDMI0_CK_N" (shape input) (at 226.06 191.77 180) (fields_autoplaced)
    (effects (font (size 1.27 1.27)) (justify right))
    (property "Intersheetrefs" "${INTERSHEET_REFS}" (at 212.0639 191.6906 0)
      (effects (font (size 1.27 1.27)) (justify right) hide)
    )
  )
  (global_label "TRD2_N" (shape input) (at 161.29 90.17 0) (fields_autoplaced)
    (effects (font (size 1.27 1.27)) (justify left))
    (property "Intersheetrefs" "${INTERSHEET_REFS}" (at 27.94 13.97 0)
      (effects (font (size 1.27 1.27)) hide)
    )
  )
  (global_label "DSI0_D0_N" (shape input) (at 262.89 151.13 0) (fields_autoplaced)
    (effects (font (size 1.27 1.27)) (justify left))
    (property "Intersheetrefs" "${INTERSHEET_REFS}" (at 275.2532 151.0506 0)
      (effects (font (size 1.27 1.27)) (justify left) hide)
    )
  )

  (symbol (lib_id "scalenode-cm4-baseboard:Compute-Module-4_H1.5mm") (at 327.152 158.369 0) (unit 1)
    (in_bom yes) (on_board yes) (dnp no)
    (property "Reference" "M1" (at 339.09 153.9239 0)
      (effects (font (size 1.27 1.27) (thickness 0.15)) (justify left bottom))
    )
    (property "Value" "Compute-Module-4_H1.5mm" (at 339.09 156.4639 0)
      (effects (font (size 1.27 1.27) (thickness 0.15)) (justify left bottom))
    )
    (property "Footprint" "scalenode-cm4-baseboard-footprints:Compute-Module-4_H1.5mm" (at 339.852 163.449 0)
      (effects (font (size 1.27 1.27) (thickness 0.15)) (justify left bottom) hide)
    )
    (property "Datasheet" "https://datasheets.raspberrypi.com/cm4/cm4-datasheet.pdf" (at 339.852 165.989 0)
      (effects (font (size 1.27 1.27) (thickness 0.15)) (justify left bottom) hide)
    )
    (property "Manufacturer" "Raspberry Pi" (at 339.852 168.529 0)
      (effects (font (size 1.27 1.27) (thickness 0.15)) (justify left bottom) hide)
    )
    (property "MPN" "SC0294" (at 343.662 176.149 0)
      (effects (font (size 1.27 1.27)) hide)
    )
    (property "Author" "Antmicro" (at 339.852 171.069 0)
      (effects (font (size 1.27 1.27) (thickness 0.15)) (justify left bottom) hide)
    )
    (property "License" "Apache-2.0" (at 339.852 173.609 0)
      (effects (font (size 1.27 1.27) (thickness 0.15)) (justify left bottom) hide)
    )
    (instances
      (project "scalenode-cm4-baseboard"
        (path ""
          (reference "M1") (unit 1)
        )
      )
    )
  )

  (symbol (lib_id "scalenode-cm4-baseboard:Socket_Hirose_DF40_2x50_DF40HC-3.0-100DS-0.4V") (at 149.86 80.01 0) (mirror y) (unit 1)
    (in_bom yes) (on_board yes) (dnp no) (fields_autoplaced)
    (property "Reference" "J7" (at 142.875 72.39 0)
      (effects (font (size 1.27 1.27) (thickness 0.15)))
    )
    (property "Value" "Socket_Hirose_DF40_2x50_DF40HC-3.0-100DS-0.4V" (at 114.3 85.09 0)
      (effects (font (size 1.27 1.27) (thickness 0.15)) (justify left bottom) hide)
    )
    (property "Footprint" "scalenode-cm4-baseboard-footprints:Conn_Socket_Hirose_DF40_2x50_DF40HC-3.0-100DS-0.4V" (at 114.3 87.63 0)
      (effects (font (size 1.27 1.27) (thickness 0.15)) (justify left bottom) hide)
    )
    (property "Datasheet" "https://www.hirose.com/en/product/document?clcode=CL0684-4151-0-51&productname=DF40HC(3.0)-100DS-0.4V(51&series=DF40&documenttype=Catalog&lang=en&documentid=en_DF40_CAT" (at 114.3 90.17 0)
      (effects (font (size 1.27 1.27) (thickness 0.15)) (justify left bottom) hide)
    )
    (property "Manufacturer" "Hirose Electric" (at 114.3 92.71 0)
      (effects (font (size 1.27 1.27) (thickness 0.15)) (justify left bottom) hide)
    )
    (property "MPN" "DF40HC(3.0)-100DS-0.4V(51)" (at 142.875 74.93 0)
      (effects (font (size 1.27 1.27) (thickness 0.15)))
    )
    (property "Author" "Antmicro" (at 114.3 97.79 0)
      (effects (font (size 1.27 1.27) (thickness 0.15)) (justify left bottom) hide)
    )
    (property "License" "Apache-2.0" (at 114.3 100.33 0)
      (effects (font (size 1.27 1.27) (thickness 0.15)) (justify left bottom) hide)
    )
    (property "Pitch" "0.4 mm" (at 114.3 95.25 0)
      (effects (font (size 1.27 1.27)) (justify left bottom) hide)
    )
    (pin "1")
    (pin "10")
    (pin "100")
    (pin "11")
    (pin "12")
    (pin "13")
    (pin "14")
    (pin "15")
    (pin "16")
    (pin "17")
    (pin "18")
    (pin "19")
    (pin "2")
    (pin "20")
    (pin "21")
    (pin "22")
    (pin "23")
    (pin "24")
    (pin "25")
    (pin "26")
    (pin "27")
    (pin "28")
    (pin "29")
    (pin "3")
    (pin "30")
    (pin "31")
    (pin "32")
    (pin "33")
    (pin "34")
    (pin "35")
    (pin "36")
    (pin "37")
    (pin "38")
    (pin "39")
    (pin "4")
    (pin "40")
    (pin "41")
    (pin "42")
    (pin "43")
    (pin "44")
    (pin "45")
    (pin "46")
    (pin "47")
    (pin "48")
    (pin "49")
    (pin "5")
    (pin "50")
    (pin "51")
    (pin "52")
    (pin "53")
    (pin "54")
    (pin "55")
    (pin "56")
    (pin "57")
    (pin "58")
    (pin "59")
    (pin "6")
    (pin "60")
    (pin "61")
    (pin "62")
    (pin "63")
    (pin "64")
    (pin "65")
    (pin "66")
    (pin "67")
    (pin "68")
    (pin "69")
    (pin "7")
    (pin "70")
    (pin "71")
    (pin "72")
    (pin "73")
    (pin "74")
    (pin "75")
    (pin "76")
    (pin "77")
    (pin "78")
    (pin "79")
    (pin "8")
    (pin "80")
    (pin "81")
    (pin "82")
    (pin "83")
    (pin "84")
    (pin "85")
    (pin "86")
    (pin "87")
    (pin "88")
    (pin "89")
    (pin "9")
    (pin "90")
    (pin "91")
    (pin "92")
    (pin "93")
    (pin "94")
    (pin "95")
    (pin "96")
    (pin "97")
    (pin "98")
    (pin "99")
    (instances
      (project "scalenode-cm4-baseboard"
        (path ""
          (reference "J7") (unit 1)
        )
      )
    )
  )

  (symbol (lib_id "scalenode-cm4-baseboard:Socket_Hirose_DF40_2x50_DF40HC-3.0-100DS-0.4V") (at 251.46 80.01 0) (mirror y) (unit 1)
    (in_bom yes) (on_board yes) (dnp no) (fields_autoplaced)
    (property "Reference" "J8" (at 244.475 72.39 0)
      (effects (font (size 1.27 1.27) (thickness 0.15)))
    )
    (property "Value" "Socket_Hirose_DF40_2x50_DF40HC-3.0-100DS-0.4V" (at 215.9 85.09 0)
      (effects (font (size 1.27 1.27) (thickness 0.15)) (justify left bottom) hide)
    )
    (property "Footprint" "scalenode-cm4-baseboard-footprints:Conn_Socket_Hirose_DF40_2x50_DF40HC-3.0-100DS-0.4V" (at 215.9 87.63 0)
      (effects (font (size 1.27 1.27) (thickness 0.15)) (justify left bottom) hide)
    )
    (property "Datasheet" "https://www.hirose.com/en/product/document?clcode=CL0684-4151-0-51&productname=DF40HC(3.0)-100DS-0.4V(51&series=DF40&documenttype=Catalog&lang=en&documentid=en_DF40_CAT" (at 215.9 90.17 0)
      (effects (font (size 1.27 1.27) (thickness 0.15)) (justify left bottom) hide)
    )
    (property "Manufacturer" "Hirose Electric" (at 215.9 92.71 0)
      (effects (font (size 1.27 1.27) (thickness 0.15)) (justify left bottom) hide)
    )
    (property "MPN" "DF40HC(3.0)-100DS-0.4V(51)" (at 244.475 74.93 0)
      (effects (font (size 1.27 1.27) (thickness 0.15)))
    )
    (property "Author" "Antmicro" (at 215.9 97.79 0)
      (effects (font (size 1.27 1.27) (thickness 0.15)) (justify left bottom) hide)
    )
    (property "License" "Apache-2.0" (at 215.9 100.33 0)
      (effects (font (size 1.27 1.27) (thickness 0.15)) (justify left bottom) hide)
    )
    (property "Pitch" "0.4 mm" (at 215.9 95.25 0)
      (effects (font (size 1.27 1.27)) (justify left bottom) hide)
    )
    (pin "1")
    (pin "10")
    (pin "100")
    (pin "11")
    (pin "12")
    (pin "13")
    (pin "14")
    (pin "15")
    (pin "16")
    (pin "17")
    (pin "18")
    (pin "19")
    (pin "2")
    (pin "20")
    (pin "21")
    (pin "22")
    (pin "23")
    (pin "24")
    (pin "25")
    (pin "26")
    (pin "27")
    (pin "28")
    (pin "29")
    (pin "3")
    (pin "30")
    (pin "31")
    (pin "32")
    (pin "33")
    (pin "34")
    (pin "35")
    (pin "36")
    (pin "37")
    (pin "38")
    (pin "39")
    (pin "4")
    (pin "40")
    (pin "41")
    (pin "42")
    (pin "43")
    (pin "44")
    (pin "45")
    (pin "46")
    (pin "47")
    (pin "48")
    (pin "49")
    (pin "5")
    (pin "50")
    (pin "51")
    (pin "52")
    (pin "53")
    (pin "54")
    (pin "55")
    (pin "56")
    (pin "57")
    (pin "58")
    (pin "59")
    (pin "6")
    (pin "60")
    (pin "61")
    (pin "62")
    (pin "63")
    (pin "64")
    (pin "65")
    (pin "66")
    (pin "67")
    (pin "68")
    (pin "69")
    (pin "7")
    (pin "70")
    (pin "71")
    (pin "72")
    (pin "73")
    (pin "74")
    (pin "75")
    (pin "76")
    (pin "77")
    (pin "78")
    (pin "79")
    (pin "8")
    (pin "80")
    (pin "81")
    (pin "82")
    (pin "83")
    (pin "84")
    (pin "85")
    (pin "86")
    (pin "87")
    (pin "88")
    (pin "89")
    (pin "9")
    (pin "90")
    (pin "91")
    (pin "92")
    (pin "93")
    (pin "94")
    (pin "95")
    (pin "96")
    (pin "97")
    (pin "98")
    (pin "99")
    (instances
      (project "scalenode-cm4-baseboard"
        (path ""
          (reference "J8") (unit 1)
        )
      )
    )
  )

  (symbol (lib_id "scalenode-cm4-baseboard:Spacer_Drill3.7mm_H3mm_9774030151R") (at 327.025 116.205 0) (unit 1)
    (in_bom yes) (on_board yes) (dnp no) (fields_autoplaced)
    (property "Reference" "SP2" (at 335.915 114.935 0)
      (effects (font (size 1.27 1.27) (thickness 0.15)) (justify left))
    )
    (property "Value" "Spacer_Drill3.7mm_H3mm_9774030151R" (at 335.915 117.475 0)
      (effects (font (size 1.27 1.27) (thickness 0.15)) (justify left))
    )
    (property "Footprint" "scalenode-cm4-baseboard-footprints:Spacer_Drill3.7mm_H3mm_9774030151R" (at 349.885 123.825 0)
      (effects (font (size 1.27 1.27) (thickness 0.15)) (justify left bottom) hide)
    )
    (property "Datasheet" "https://www.we-online.com/catalog/datasheet/9774030151.pdf" (at 349.885 126.365 0)
      (effects (font (size 1.27 1.27) (thickness 0.15)) (justify left bottom) hide)
    )
    (property "Manufacturer" "Würth Elektronik" (at 349.885 128.905 0)
      (effects (font (size 1.27 1.27) (thickness 0.15)) (justify left bottom) hide)
    )
    (property "MPN" "9774030151R" (at 349.885 131.445 0)
      (effects (font (size 1.27 1.27) (thickness 0.15)) (justify left bottom) hide)
    )
    (property "Author" "Antmicro" (at 349.885 133.985 0)
      (effects (font (size 1.27 1.27) (thickness 0.15)) (justify left bottom) hide)
    )
    (property "License" "Apache-2.0" (at 349.885 136.525 0)
      (effects (font (size 1.27 1.27) (thickness 0.15)) (justify left bottom) hide)
    )
    (pin "1")
    (instances
      (project "scalenode-cm4-baseboard"
        (path ""
          (reference "SP2") (unit 1)
        )
      )
    )
  )

  (symbol (lib_id "scalenode-cm4-baseboard:Spacer_Drill3.7mm_H3mm_9774030151R") (at 327.025 125.095 0) (unit 1)
    (in_bom yes) (on_board yes) (dnp no) (fields_autoplaced)
    (property "Reference" "SP3" (at 335.915 123.825 0)
      (effects (font (size 1.27 1.27) (thickness 0.15)) (justify left))
    )
    (property "Value" "Spacer_Drill3.7mm_H3mm_9774030151R" (at 335.915 126.365 0)
      (effects (font (size 1.27 1.27) (thickness 0.15)) (justify left))
    )
    (property "Footprint" "scalenode-cm4-baseboard-footprints:Spacer_Drill3.7mm_H3mm_9774030151R" (at 349.885 132.715 0)
      (effects (font (size 1.27 1.27) (thickness 0.15)) (justify left bottom) hide)
    )
    (property "Datasheet" "https://www.we-online.com/catalog/datasheet/9774030151.pdf" (at 349.885 135.255 0)
      (effects (font (size 1.27 1.27) (thickness 0.15)) (justify left bottom) hide)
    )
    (property "Manufacturer" "Würth Elektronik" (at 349.885 137.795 0)
      (effects (font (size 1.27 1.27) (thickness 0.15)) (justify left bottom) hide)
    )
    (property "MPN" "9774030151R" (at 349.885 140.335 0)
      (effects (font (size 1.27 1.27) (thickness 0.15)) (justify left bottom) hide)
    )
    (property "Author" "Antmicro" (at 349.885 142.875 0)
      (effects (font (size 1.27 1.27) (thickness 0.15)) (justify left bottom) hide)
    )
    (property "License" "Apache-2.0" (at 349.885 145.415 0)
      (effects (font (size 1.27 1.27) (thickness 0.15)) (justify left bottom) hide)
    )
    (pin "1")
    (instances
      (project "scalenode-cm4-baseboard"
        (path ""
          (reference "SP3") (unit 1)
        )
      )
    )
  )

  (symbol (lib_id "scalenode-cm4-baseboard:Spacer_Drill3.7mm_H3mm_9774030151R") (at 327.025 134.62 0) (unit 1)
    (in_bom yes) (on_board yes) (dnp no) (fields_autoplaced)
    (property "Reference" "SP4" (at 335.915 133.35 0)
      (effects (font (size 1.27 1.27) (thickness 0.15)) (justify left))
    )
    (property "Value" "Spacer_Drill3.7mm_H3mm_9774030151R" (at 335.915 135.89 0)
      (effects (font (size 1.27 1.27) (thickness 0.15)) (justify left))
    )
    (property "Footprint" "scalenode-cm4-baseboard-footprints:Spacer_Drill3.7mm_H3mm_9774030151R" (at 349.885 142.24 0)
      (effects (font (size 1.27 1.27) (thickness 0.15)) (justify left bottom) hide)
    )
    (property "Datasheet" "https://www.we-online.com/catalog/datasheet/9774030151.pdf" (at 349.885 144.78 0)
      (effects (font (size 1.27 1.27) (thickness 0.15)) (justify left bottom) hide)
    )
    (property "Manufacturer" "Würth Elektronik" (at 349.885 147.32 0)
      (effects (font (size 1.27 1.27) (thickness 0.15)) (justify left bottom) hide)
    )
    (property "MPN" "9774030151R" (at 349.885 149.86 0)
      (effects (font (size 1.27 1.27) (thickness 0.15)) (justify left bottom) hide)
    )
    (property "Author" "Antmicro" (at 349.885 152.4 0)
      (effects (font (size 1.27 1.27) (thickness 0.15)) (justify left bottom) hide)
    )
    (property "License" "Apache-2.0" (at 349.885 154.94 0)
      (effects (font (size 1.27 1.27) (thickness 0.15)) (justify left bottom) hide)
    )
    (pin "1")
    (instances
      (project "scalenode-cm4-baseboard"
        (path ""
          (reference "SP4") (unit 1)
        )
      )
    )
  )

  (symbol (lib_id "scalenode-cm4-baseboard:Spacer_Drill3.7mm_H3mm_9774030151R") (at 327.025 143.51 0) (unit 1)
    (in_bom yes) (on_board yes) (dnp no) (fields_autoplaced)
    (property "Reference" "SP5" (at 335.915 142.24 0)
      (effects (font (size 1.27 1.27) (thickness 0.15)) (justify left))
    )
    (property "Value" "Spacer_Drill3.7mm_H3mm_9774030151R" (at 335.915 144.78 0)
      (effects (font (size 1.27 1.27) (thickness 0.15)) (justify left))
    )
    (property "Footprint" "scalenode-cm4-baseboard-footprints:Spacer_Drill3.7mm_H3mm_9774030151R" (at 349.885 151.13 0)
      (effects (font (size 1.27 1.27) (thickness 0.15)) (justify left bottom) hide)
    )
    (property "Datasheet" "https://www.we-online.com/catalog/datasheet/9774030151.pdf" (at 349.885 153.67 0)
      (effects (font (size 1.27 1.27) (thickness 0.15)) (justify left bottom) hide)
    )
    (property "Manufacturer" "Würth Elektronik" (at 349.885 156.21 0)
      (effects (font (size 1.27 1.27) (thickness 0.15)) (justify left bottom) hide)
    )
    (property "MPN" "9774030151R" (at 349.885 158.75 0)
      (effects (font (size 1.27 1.27) (thickness 0.15)) (justify left bottom) hide)
    )
    (property "Author" "Antmicro" (at 349.885 161.29 0)
      (effects (font (size 1.27 1.27) (thickness 0.15)) (justify left bottom) hide)
    )
    (property "License" "Apache-2.0" (at 349.885 163.83 0)
      (effects (font (size 1.27 1.27) (thickness 0.15)) (justify left bottom) hide)
    )
    (pin "1")
    (instances
      (project "scalenode-cm4-baseboard"
        (path ""
          (reference "SP5") (unit 1)
        )
      )
    )
  )

  (symbol (lib_id "scalenode-cm4-baseboard:LED_G_0603_598-8D80-107F") (at 176.53 105.41 180) (unit 1)
    (in_bom yes) (on_board yes) (dnp no)
    (property "Reference" "D11" (at 177.8 101.6 0)
      (effects (font (size 1.27 1.27) (thickness 0.15)) (justify left bottom))
    )
    (property "Value" "LED_G_0603_598-8D80-107F" (at 186.9011 101.6 0)
      (effects (font (size 1.27 1.27) (thickness 0.15)) (justify left bottom) hide)
    )
    (property "Footprint" "scalenode-cm4-baseboard-footprints:LED_0603_1608Metric_G" (at 153.67 97.79 0)
      (effects (font (size 1.27 1.27) (thickness 0.15)) (justify left bottom) hide)
    )
    (property "Datasheet" "https://www.farnell.com/datasheets/3093797.pdf" (at 153.67 95.25 0)
      (effects (font (size 1.27 1.27) (thickness 0.15)) (justify left bottom) hide)
    )
    (property "MPN" "598-8D80-107F" (at 153.67 92.71 0)
      (effects (font (size 1.27 1.27) (thickness 0.15)) (justify left bottom) hide)
    )
    (property "Manufacturer" "Dialight" (at 153.67 90.17 0)
      (effects (font (size 1.27 1.27) (thickness 0.15)) (justify left bottom) hide)
    )
    (property "Author" "Antmicro" (at 153.67 87.63 0)
      (effects (font (size 1.27 1.27) (thickness 0.15)) (justify left bottom) hide)
    )
    (property "License" "Apache-2.0" (at 153.67 85.09 0)
      (effects (font (size 1.27 1.27) (thickness 0.15)) (justify left bottom) hide)
    )
    (pin "1")
    (pin "2")
    (instances
      (project "scalenode-cm4-baseboard"
        (path ""
          (reference "D11") (unit 1)
        )
      )
    )
  )

  (symbol (lib_id "scalenode-cm4-baseboard:GND") (at 152.4 213.36 0) (unit 1)
    (in_bom yes) (on_board yes) (dnp no) (fields_autoplaced)
    (property "Reference" "#PWR0101" (at 161.29 215.9 0)
      (effects (font (size 1.27 1.27) (thickness 0.15)) (justify left bottom) hide)
    )
    (property "Value" "GND" (at 150.3898 218.44 0)
      (effects (font (size 1.27 1.27) (thickness 0.15)) (justify left bottom))
    )
    (property "Footprint" "" (at 161.29 220.98 0)
      (effects (font (size 1.27 1.27) (thickness 0.15)) (justify left bottom) hide)
    )
    (property "Datasheet" "" (at 161.29 226.06 0)
      (effects (font (size 1.27 1.27) (thickness 0.15)) (justify left bottom) hide)
    )
    (property "Author" "Antmicro" (at 161.29 220.98 0)
      (effects (font (size 1.27 1.27) (thickness 0.15)) (justify left bottom) hide)
    )
    (property "License" "Apache-2.0" (at 161.29 223.52 0)
      (effects (font (size 1.27 1.27) (thickness 0.15)) (justify left bottom) hide)
    )
    (pin "1")
    (instances
      (project "scalenode-cm4-baseboard"
        (path ""
          (reference "#PWR0101") (unit 1)
        )
      )
    )
  )

  (symbol (lib_id "scalenode-cm4-baseboard:GND") (at 133.35 213.36 0) (unit 1)
    (in_bom yes) (on_board yes) (dnp no) (fields_autoplaced)
    (property "Reference" "#PWR0102" (at 142.24 215.9 0)
      (effects (font (size 1.27 1.27) (thickness 0.15)) (justify left bottom) hide)
    )
    (property "Value" "GND" (at 131.3398 218.44 0)
      (effects (font (size 1.27 1.27) (thickness 0.15)) (justify left bottom))
    )
    (property "Footprint" "" (at 142.24 220.98 0)
      (effects (font (size 1.27 1.27) (thickness 0.15)) (justify left bottom) hide)
    )
    (property "Datasheet" "" (at 142.24 226.06 0)
      (effects (font (size 1.27 1.27) (thickness 0.15)) (justify left bottom) hide)
    )
    (property "Author" "Antmicro" (at 142.24 220.98 0)
      (effects (font (size 1.27 1.27) (thickness 0.15)) (justify left bottom) hide)
    )
    (property "License" "Apache-2.0" (at 142.24 223.52 0)
      (effects (font (size 1.27 1.27) (thickness 0.15)) (justify left bottom) hide)
    )
    (pin "1")
    (instances
      (project "scalenode-cm4-baseboard"
        (path ""
          (reference "#PWR0102") (unit 1)
        )
      )
    )
  )

  (symbol (lib_id "scalenode-cm4-baseboard:GND") (at 233.68 214.63 0) (unit 1)
    (in_bom yes) (on_board yes) (dnp no) (fields_autoplaced)
    (property "Reference" "#PWR0103" (at 242.57 217.17 0)
      (effects (font (size 1.27 1.27) (thickness 0.15)) (justify left bottom) hide)
    )
    (property "Value" "GND" (at 231.6698 219.71 0)
      (effects (font (size 1.27 1.27) (thickness 0.15)) (justify left bottom))
    )
    (property "Footprint" "" (at 242.57 222.25 0)
      (effects (font (size 1.27 1.27) (thickness 0.15)) (justify left bottom) hide)
    )
    (property "Datasheet" "" (at 242.57 227.33 0)
      (effects (font (size 1.27 1.27) (thickness 0.15)) (justify left bottom) hide)
    )
    (property "Author" "Antmicro" (at 242.57 222.25 0)
      (effects (font (size 1.27 1.27) (thickness 0.15)) (justify left bottom) hide)
    )
    (property "License" "Apache-2.0" (at 242.57 224.79 0)
      (effects (font (size 1.27 1.27) (thickness 0.15)) (justify left bottom) hide)
    )
    (pin "1")
    (instances
      (project "scalenode-cm4-baseboard"
        (path ""
          (reference "#PWR0103") (unit 1)
        )
      )
    )
  )

  (symbol (lib_id "scalenode-cm4-baseboard:GND") (at 254 214.63 0) (unit 1)
    (in_bom yes) (on_board yes) (dnp no) (fields_autoplaced)
    (property "Reference" "#PWR0104" (at 262.89 217.17 0)
      (effects (font (size 1.27 1.27) (thickness 0.15)) (justify left bottom) hide)
    )
    (property "Value" "GND" (at 251.9898 219.71 0)
      (effects (font (size 1.27 1.27) (thickness 0.15)) (justify left bottom))
    )
    (property "Footprint" "" (at 262.89 222.25 0)
      (effects (font (size 1.27 1.27) (thickness 0.15)) (justify left bottom) hide)
    )
    (property "Datasheet" "" (at 262.89 227.33 0)
      (effects (font (size 1.27 1.27) (thickness 0.15)) (justify left bottom) hide)
    )
    (property "Author" "Antmicro" (at 262.89 222.25 0)
      (effects (font (size 1.27 1.27) (thickness 0.15)) (justify left bottom) hide)
    )
    (property "License" "Apache-2.0" (at 262.89 224.79 0)
      (effects (font (size 1.27 1.27) (thickness 0.15)) (justify left bottom) hide)
    )
    (pin "1")
    (instances
      (project "scalenode-cm4-baseboard"
        (path ""
          (reference "#PWR0104") (unit 1)
        )
      )
    )
  )

  (symbol (lib_id "scalenode-cm4-baseboard:R_1k_0603") (at 157.48 105.41 0) (unit 1)
    (in_bom yes) (on_board yes) (dnp no)
    (property "Reference" "R42" (at 157.48 104.14 0)
      (effects (font (size 1.27 1.27) (thickness 0.15)) (justify left bottom))
    )
    (property "Value" "R_1k_0603" (at 177.8 118.11 0)
      (effects (font (size 1.27 1.27) (thickness 0.15)) (justify left bottom) hide)
    )
    (property "Footprint" "scalenode-cm4-baseboard-footprints:R_0603_1608Metric" (at 177.8 120.65 0)
      (effects (font (size 1.27 1.27) (thickness 0.15)) (justify left bottom) hide)
    )
    (property "Datasheet" "https://www.bourns.com/docs/product-datasheets/cr.pdf" (at 177.8 123.19 0)
      (effects (font (size 1.27 1.27) (thickness 0.15)) (justify left bottom) hide)
    )
    (property "Manufacturer" "Bourns" (at 177.8 128.27 0)
      (effects (font (size 1.27 1.27) (thickness 0.15)) (justify left bottom) hide)
    )
    (property "MPN" "CR0603-FX-1001ELF" (at 177.8 125.73 0)
      (effects (font (size 1.27 1.27) (thickness 0.15)) (justify left bottom) hide)
    )
    (property "Val" "1k" (at 157.48 109.22 0)
      (effects (font (size 1.27 1.27) (thickness 0.15)) (justify left bottom))
    )
    (property "License" "Apache-2.0" (at 177.8 130.81 0)
      (effects (font (size 1.27 1.27) (thickness 0.15)) (justify left bottom) hide)
    )
    (property "Author" "Antmicro" (at 177.8 133.35 0)
      (effects (font (size 1.27 1.27) (thickness 0.15)) (justify left bottom) hide)
    )
    (property "Tolerance" "1%" (at 177.8 115.57 0)
      (effects (font (size 1.27 1.27)) (justify left bottom) hide)
    )
    (pin "1")
    (pin "2")
    (instances
      (project "scalenode-cm4-baseboard"
        (path ""
          (reference "R42") (unit 1)
        )
      )
    )
  )

  (symbol (lib_id "scalenode-cm4-baseboard:BSS138-7-F") (at 182.88 210.82 0) (unit 1)
    (in_bom yes) (on_board yes) (dnp no)
    (property "Reference" "Q6" (at 193.04 208.28 0)
      (effects (font (size 1.27 1.27) (thickness 0.15)) (justify left bottom))
    )
    (property "Value" "BSS138-7-F" (at 193.04 210.82 0)
      (effects (font (size 1.27 1.27) (thickness 0.15)) (justify left bottom))
    )
    (property "Footprint" "scalenode-cm4-baseboard-footprints:SOT-23-3" (at 205.74 213.36 0)
      (effects (font (size 1.27 1.27) (thickness 0.15)) (justify left bottom) hide)
    )
    (property "Datasheet" "https://www.diodes.com/assets/Datasheets/ds30144.pdf" (at 205.74 215.9 0)
      (effects (font (size 1.27 1.27) (thickness 0.15)) (justify left bottom) hide)
    )
    (property "MPN" "BSS138-7-F" (at 205.74 218.44 0)
      (effects (font (size 1.27 1.27) (thickness 0.15)) (justify left bottom) hide)
    )
    (property "Manufacturer" "Diodes Incorporated" (at 205.74 220.98 0)
      (effects (font (size 1.27 1.27) (thickness 0.15)) (justify left bottom) hide)
    )
    (property "Author" "Antmicro" (at 205.74 223.52 0)
      (effects (font (size 1.27 1.27) (thickness 0.15)) (justify left bottom) hide)
    )
    (property "License" "Apache-2.0" (at 205.74 226.06 0)
      (effects (font (size 1.27 1.27) (thickness 0.15)) (justify left bottom) hide)
    )
    (pin "1")
    (pin "2")
    (pin "3")
    (instances
      (project "scalenode-cm4-baseboard"
        (path ""
          (reference "Q6") (unit 1)
        )
      )
    )
  )

  (symbol (lib_id "scalenode-cm4-baseboard:GND") (at 190.5 223.52 0) (unit 1)
    (in_bom yes) (on_board yes) (dnp no) (fields_autoplaced)
    (property "Reference" "#PWR048" (at 199.39 226.06 0)
      (effects (font (size 1.27 1.27) (thickness 0.15)) (justify left bottom) hide)
    )
    (property "Value" "GND" (at 188.4898 228.6 0)
      (effects (font (size 1.27 1.27) (thickness 0.15)) (justify left bottom))
    )
    (property "Footprint" "" (at 199.39 231.14 0)
      (effects (font (size 1.27 1.27) (thickness 0.15)) (justify left bottom) hide)
    )
    (property "Datasheet" "" (at 199.39 236.22 0)
      (effects (font (size 1.27 1.27) (thickness 0.15)) (justify left bottom) hide)
    )
    (property "Author" "Antmicro" (at 199.39 231.14 0)
      (effects (font (size 1.27 1.27) (thickness 0.15)) (justify left bottom) hide)
    )
    (property "License" "Apache-2.0" (at 199.39 233.68 0)
      (effects (font (size 1.27 1.27) (thickness 0.15)) (justify left bottom) hide)
    )
    (pin "1")
    (instances
      (project "scalenode-cm4-baseboard"
        (path ""
          (reference "#PWR048") (unit 1)
        )
      )
    )
  )

  (symbol (lib_id "scalenode-cm4-baseboard:R_10k_0402") (at 181.61 213.36 270) (unit 1)
    (in_bom yes) (on_board yes) (dnp no)
    (property "Reference" "R65" (at 182.88 215.9 90)
      (effects (font (size 1.27 1.27) (thickness 0.15)) (justify left bottom))
    )
    (property "Value" "R_10k_0402" (at 168.91 233.68 0)
      (effects (font (size 1.27 1.27) (thickness 0.15)) (justify left bottom) hide)
    )
    (property "Footprint" "scalenode-cm4-baseboard-footprints:R_0402_1005Metric" (at 166.37 233.68 0)
      (effects (font (size 1.27 1.27) (thickness 0.15)) (justify left bottom) hide)
    )
    (property "Datasheet" "https://www.bourns.com/docs/product-datasheets/cr.pdf" (at 163.83 233.68 0)
      (effects (font (size 1.27 1.27) (thickness 0.15)) (justify left bottom) hide)
    )
    (property "Manufacturer" "Bourns" (at 158.75 233.68 0)
      (effects (font (size 1.27 1.27) (thickness 0.15)) (justify left bottom) hide)
    )
    (property "MPN" "CR0402-FX-1002GLF" (at 161.29 233.68 0)
      (effects (font (size 1.27 1.27) (thickness 0.15)) (justify left bottom) hide)
    )
    (property "Val" "10k" (at 182.88 218.44 90)
      (effects (font (size 1.27 1.27) (thickness 0.15)) (justify left bottom))
    )
    (property "License" "Apache-2.0" (at 156.21 233.68 0)
      (effects (font (size 1.27 1.27) (thickness 0.15)) (justify left bottom) hide)
    )
    (property "Author" "Antmicro" (at 153.67 233.68 0)
      (effects (font (size 1.27 1.27) (thickness 0.15)) (justify left bottom) hide)
    )
    (property "Tolerance" "1%" (at 171.45 233.68 0)
      (effects (font (size 1.27 1.27)) (justify left bottom) hide)
    )
    (pin "1")
    (pin "2")
    (instances
      (project "scalenode-cm4-baseboard"
        (path ""
          (reference "R65") (unit 1)
        )
      )
    )
  )

  (symbol (lib_id "scalenode-cm4-baseboard:R_470R_0402") (at 172.72 210.82 0) (unit 1)
    (in_bom yes) (on_board yes) (dnp no)
    (property "Reference" "R64" (at 172.72 209.55 0)
      (effects (font (size 1.27 1.27) (thickness 0.15)) (justify left bottom))
    )
    (property "Value" "R_470R_0402" (at 193.04 223.52 0)
      (effects (font (size 1.27 1.27) (thickness 0.15)) (justify left bottom) hide)
    )
    (property "Footprint" "scalenode-cm4-baseboard-footprints:R_0402_1005Metric" (at 193.04 226.06 0)
      (effects (font (size 1.27 1.27) (thickness 0.15)) (justify left bottom) hide)
    )
    (property "Datasheet" "https://www.bourns.com/docs/product-datasheets/cr.pdf" (at 193.04 228.6 0)
      (effects (font (size 1.27 1.27) (thickness 0.15)) (justify left bottom) hide)
    )
    (property "Manufacturer" "Bourns" (at 193.04 233.68 0)
      (effects (font (size 1.27 1.27) (thickness 0.15)) (justify left bottom) hide)
    )
    (property "MPN" "CR0402-FX-4700GLF" (at 193.04 231.14 0)
      (effects (font (size 1.27 1.27) (thickness 0.15)) (justify left bottom) hide)
    )
    (property "Val" "470R" (at 172.72 214.63 0)
      (effects (font (size 1.27 1.27) (thickness 0.15)) (justify left bottom))
    )
    (property "License" "Apache-2.0" (at 193.04 236.22 0)
      (effects (font (size 1.27 1.27) (thickness 0.15)) (justify left bottom) hide)
    )
    (property "Author" "Antmicro" (at 193.04 238.76 0)
      (effects (font (size 1.27 1.27) (thickness 0.15)) (justify left bottom) hide)
    )
    (property "Tolerance" "1%" (at 193.04 220.98 0)
      (effects (font (size 1.27 1.27)) (justify left bottom) hide)
    )
    (pin "1")
    (pin "2")
    (instances
      (project "scalenode-cm4-baseboard"
        (path ""
          (reference "R64") (unit 1)
        )
      )
    )
  )

  (symbol (lib_id "scalenode-cm4-baseboard:TP_1mm_SMD") (at 129.54 186.69 90) (unit 1)
    (in_bom yes) (on_board yes) (dnp no)
    (property "Reference" "TP6" (at 128.27 182.88 90)
      (effects (font (size 1.27 1.27) (thickness 0.15)) (justify left bottom))
    )
    (property "Value" "TP_1mm_SMD" (at 137.16 171.45 0)
      (effects (font (size 1.27 1.27) (thickness 0.15)) (justify left bottom) hide)
    )
    (property "Footprint" "scalenode-cm4-baseboard-footprints:TP_SMD_1mm" (at 139.7 171.45 0)
      (effects (font (size 1.27 1.27) (thickness 0.15)) (justify left bottom) hide)
    )
    (property "Datasheet" "" (at 142.24 171.45 0)
      (effects (font (size 1.27 1.27) (thickness 0.15)) (justify left bottom) hide)
    )
    (property "Author" "Antmicro" (at 144.78 171.45 0)
      (effects (font (size 1.27 1.27) (thickness 0.15)) (justify left bottom) hide)
    )
    (property "License" "Apache-2.0" (at 147.32 171.45 0)
      (effects (font (size 1.27 1.27) (thickness 0.15)) (justify left bottom) hide)
    )
    (property "MPN" "" (at 129.54 186.69 0)
      (effects (font (size 1.27 1.27)) hide)
    )
    (property "Manufacturer" "" (at 129.54 186.69 0)
      (effects (font (size 1.27 1.27)) hide)
    )
    (pin "1")
    (instances
      (project "scalenode-cm4-baseboard"
        (path ""
          (reference "TP6") (unit 1)
        )
      )
    )
  )
)
